# Barreleye-G2_Tri-mode Expander-DVT-X01-SKU-BOM-X07-20171222_Final.xls.xlsx — Changelist (bom)
| BOM Change List Date:Sat May 27 11:46:00 GMT+08:00 2017 |  |  |  |  |  |  |  |  |  |
| New BOM file : C:\<user>\Barreleye_G2-Tri-mode BPX24-EVT-X00-BOM-X01_20170509.xls |  |  |  |  |  |  |  |  |  |
| Old BOM file : C:\<user>\Barreleye_G2-TRI-MODE BPX24-EVT-X00-BOM-X00-20170420.xls |  |  |  |  |  |  |  |  |  |
| ##### Add Parts |  |  |  |  |  |  |  |  |  |
| Item | Location | Qty | Foxconn P/N | Part Description | Manufacturer Full Name | Manufacturer P/N | RoHS | Sheet |  |
| 1 | C15,C19,C216,C217,C224,C2101,C2102,C2103,C2104,C2105,C2106,C2107,C2108,C2109,C2110,C2111,C2112,C2113,C2114,C2115,C2116,C2117,C2118,C2119,C2120,C2121,C2122,C2123,C2124,C2125,C2126,C2127,C2128,C2129,C2130,C2131,C2132,C2133,C2134,C2135,C2136,C2137,C2138,C2139,C2140,C2141,C2142,C2143,C2144,C2145,C2146,C2147,C2148,C2149,C2169,C2171,C2176,C2177,C2178,C2179,C2180,C2181,C2182,C2183,C2184,C2185,C2186,C2187,C2188,C2189,C2190,C2191,C2192,C2193,C2194,C2195,C2196,C2197,C2232,C2233,C2234,C2235,C2237,C2239,C2240,C2241,C2242,C2254,C2255,C2256,C2259,C2260,C2261,C2262,C2263,C2264,C2265,C2266 | 98 | 620101T02-015-G | CAP,100nF,+/-10%,X7R,16V,G,SMD0402 | MURATA ELEC. NORTH AMERICA | GRM155R71C104K | Y | PWA BOM |  |
|  |  |  | 620101T00-012-G | CAP,100nF,+/-10%,X7R,16V,G,SMD0402 | WALSIN | 0402B104K160CT |  | PWA BOM |  |
|  |  |  | 620101T00-026-G | CAP,100nF,+/-10%,X7R,16V,G,SMD0402 | SAMSUNG SEMICONDUCTOR | CL05B104KO5NNNC |  | PWA BOM |  |
|  |  |  | 620101T00-015-G | CAP,100nF,+/-10%,X7R,16V,G,SMD0402 | MURATA ELEC. NORTH AMERICA | GRM155R71C104KA88D |  | PWA BOM |  |
| 2 | C2236,C2238 | 2 | 620100A00-015-G | CAP,10uF,+/-10%,X5R,16V,G,SMD1206 | MURATA ELEC. NORTH AMERICA | GRM31CR61C106K | N | PWA BOM |  |
|  |  |  | 620100A00-026-G | CAP,10uF,+/-10%,X5R,16V,G,SMD1206 | SAMSUNG SEMICONDUCTOR | CL31A106KOHNNNE | G | PWA BOM |  |
|  |  |  | 620100A03-023-G | CAP,10uF,+/-10%,X5R,16V,G,SMD1206 | TAIYO ELECTRIC IND.CO.LTD | EMK316BJ106KL-T | G | PWA BOM |  |
|  |  |  | 620100A00-012-G | CAP,10uF,+/-10%,X5R,16V,G,SMD1206 | WALSIN TECHNOLOGY CORPORATION | 1206X106K160CT | G | PWA BOM |  |
|  |  |  | 620100A00-011-G | CAP,10uF,+/-10%,X5R,16V,G,SMD1206 | YAGEO CORPORATION COMPONENT | CC1206KKX5R7BB106 | G | PWA BOM |  |
| 3 | C215 | 1 | 620105E00-015-G | CAP,1uF,+/-10%,X7R,10V,G,SMD0603 | MURATA ELEC. NORTH AMERICA | GRM188R71A105K |  | PWA BOM |  |
|  |  |  | 620105E00-012-G | CAP,1uF,+/-10%,X7R,10V,G,SMD0603 | WALSIN TECHNOLOGY CORPORATION | 0603B105K100CT | G | PWA BOM |  |
|  |  |  | 620105E00-011-G | CAP,1uF,+/-10%,X7R,10V,G,SMD0603 | YAGEO CORPORATION COMPONENT | CC0603KRX7R6BB105 | G | PWA BOM |  |
|  |  |  | 620105E00-026-G | CAP,1uF,+/-10%,X7R,10V,G,SMD0603 | SAMSUNG SEMICONDUCTOR | CL10B105KP8NNNC | G | PWA BOM |  |
|  |  |  | 620105E01-023-G | CAP,1uF,+/-10%,X7R,10V,G,SMD0603 | TAIYO ELECTRIC IND.CO.LTD | LMK107B7105KA-T | G | PWA BOM |  |
| 4 | C218,C219,C220,C221,C222,C2243,C2244,C2251,C2252 | 9 | 620103600-015-G | CAP,10nF,+/-10%,X7R,25V,G,SMD0402 | MURATA ELEC. NORTH AMERICA | GRM155R71E103K | N | PWA BOM |  |
|  |  |  | 620103600-012-G | CAP,10nF,+/-10%,X7R,25V,G,SMD0402 | WALSIN TECHNOLOGY CORPORATION | 0402B103K250CT | G | PWA BOM |  |
|  |  |  | 620103600-011-G | CAP,10nF,+/-10%,X7R,25V,G,SMD0402 | YAGEO CORPORATION COMPONENT | CC0402KRX7R8BB103 | G | PWA BOM |  |
|  |  |  | 620103600-026-G | CAP,10nF,+/-10%,X7R,25V,G,SMD0402 | SAMSUNG SEMICONDUCTOR | CL05B103KA5NNNC | G | PWA BOM |  |
|  |  |  | 620103601-023-G | CAP,10nF,+/-10%,X7R,25V,G,SMD0402 | TAIYO ELECTRIC IND.CO.LTD | TMK105B7103KV-F | G | PWA BOM |  |
| 5 | C214 | 1 | 62010L000-015-G | CAP,10uF,+/-20%,X5R,6.3V,G,SMD0603 | MURATA ELEC. NORTH AMERICA | GRM188R60J106M | N | PWA BOM |  |
|  |  |  | 62010L000-023-G | CAP,10uF,+/-20%,X5R,6.3V,G,SMD0603 | TAIYO ELECTRIC IND.CO.LTD | JMK107BJ106MA-T | G | PWA BOM |  |
|  |  |  | 62010L000-012-G | CAP,10uF,+/-20%,X5R,6.3V,G,SMD0603 | WALSIN TECHNOLOGY CORPORATION | 0603X106M6R3CT | G | PWA BOM |  |
|  |  |  | 62010L000-026-G | CAP,10uF,+/-20%,X5R,6.3V,G,SMD0603 | SAMSUNG SEMICONDUCTOR | CL10A106MQ8NNNC | G | PWA BOM |  |
|  |  |  | 62010L000-011-G | CAP,10uF,+/-20%,X5R,6.3V,G,SMD0603 | YAGEO CORPORATION COMPONENT | CC0603MRX5R5BB106 | G | PWA BOM |  |
| 6 | C223 | 1 | 62011NF01-015-G | CAP,2.2uF,+/-10%,X7R,25V,G,SMD0805 | MURATA ELEC. NORTH AMERICA | GRM21BR71E225K |  | PWA BOM |  |
|  |  |  | 62011NF00-026-G | CAP,2.2uF,+/-10%,X7R,25V,G,SMD0805 | SAMSUNG SEMICONDUCTOR | CL21B225KAFNNNE |  | PWA BOM |  |
|  |  |  | 62011NF00-023-G | CAP,2.2uF,+/-10%,X7R,25V,G,SMD0805 | TAIYO ELECTRIC IND.CO.LTD | TMK212B7225KG-TR |  | PWA BOM |  |
| 7 | C1946,C2081,C2253 | 3 | 620114000-015-G | CAP,10uF,+/-10%,X5R,16V,G,SMD0805 | MURATA ELEC. NORTH AMERICA | GRM21BR61C106K | N | PWA BOM |  |
| 8 | C1950,C2080,C2245,C2246,C2247,C2248,C2249,C2250,C2257,C2258 | 10 | 620105400-015-G | CAP,1uF,+/-10%,X7R,16V,G,SMD0603 | MURATA ELEC. NORTH AMERICA | GRM188R71C105K | N | PWA BOM |  |
|  |  |  | 620105400-012-G | CAP,1uF,+/-10%,X7R,16V,G,SMD0603 | WALSIN TECHNOLOGY CORPORATION | 0603B105K160CT | G | PWA BOM |  |
|  |  |  | 620105400-011-G | CAP,1uF,+/-10%,X7R,16V,G,SMD0603 | YAGEO CORPORATION COMPONENT | CC0603KRX7R7BB105 | G | PWA BOM |  |
|  |  |  | 620105400-026-G | CAP,1uF,+/-10%,X7R,16V,G,SMD0603 | SAMSUNG SEMICONDUCTOR | CL10B105KO8NNNC | G | PWA BOM |  |
|  |  |  | 620105400-023-G | CAP,1uF,+/-10%,X7R,16V,G,SMD0603 | TAIYO ELECTRIC IND.CO.LTD | EMK107B7105KA-T | G | PWA BOM |  |
| 9 | C2198,C2208,C2209,C2210,C2211,C2212,C2213,C2214,C2215,C2216,C2217,C2218,C2219,C2220,C2221,C2222,C2223,C2224 | 18 | 62011LU00-015-G | CAP,100nF,+/-10%,X5R,16V,G,SMD0402 | MURATA ELEC. NORTH AMERICA | GRM155R61C104KA88D | Y | PWA BOM |  |
| 10 | C2231 | 1 | 620109S00-015-G | CAP,4.7uF,+/-10%,X7R,10V,G,SMD0805 | MURATA ELEC. NORTH AMERICA | GRM21BR71A475K | N | PWA BOM |  |
|  |  |  | 620109S00-023-G | CAP,4.7uF,+/-10%,X7R,10V,G,SMD0805 | TAIYO ELECTRIC IND.CO.LTD | LMK212B7475KG-T |  | PWA BOM |  |
|  |  |  | 620109S00-026-G | CAP,4.7uF,+/-10%,X7R,10V,G,SMD0805 | SAMSUNG SEMICONDUCTOR | CL21B475KPFNNNE |  | PWA BOM |  |
| 11 | C2267 | 1 | 620106200-015-G | CAP,10nF,+/-10%,X7R,16V,G,SMD0402 | MURATA ELEC. NORTH AMERICA | GRM155R71C103K | N | PWA BOM |  |
|  |  |  | 620106200-012-G | CAP,10nF,+/-10%,X7R,16V,G,SMD0402 | WALSIN | 0402B103K160CT | G | PWA BOM |  |
|  |  |  | 620106200-026-G | CAP,10nF,+/-10%,X7R,16V,G,SMD0402 | SAMSUNG | CL05B103KO5NNNC | G | PWA BOM |  |
|  |  |  | 620106200-023-G | CAP,10nF,+/-10%,X7R,16V,G,SMD0402 | TAIYO | EMK105B7103KV-F | G | PWA BOM |  |
| 12 | C2268,C2269 | 2 | 62012UW00-015-G | CAP,6.8pF,+/-0.05pF,NPO(C0G),25V,G,SMD0402 | MURATA ELEC. NORTH AMERICA | GRM1555C1E6R8WA01D |  | PWA BOM |  |
| 13 | L4 | 1 | 72010JY00-015-G | FB,330 Ohm@100MHz,+/-25%,1.5A,70mOhm,G,SMD0603 | MURATA ELEC. NORTH AMERICA | BLM18SG331TN1D | N | PWA BOM |  |
|  |  |  | 72010JB00-016-G | FB,330 Ohm@100MHz,+/-25%,1.5A,G,80mOhm,SMD0603 | TDK ELECTRONICS EUROPE GMBH | MPZ1608S331AT |  | PWA BOM |  |
| 14 | L6,L28 | 2 | 72010FB01-016-G | FB,600 Ohm@100MHz,+/-25%,1A,150mOhm,G,SMD0603 | TDK ELECTRONICS EUROPE GMBH | MPZ1608S601AT | N | PWA BOM |  |
| 15 | L30 | 1 | 720102001-015-G | FB,30 Ohm@100MHz,+/-25%,3A,15mOhm,G,SMD0805 | MURATA ELEC. NORTH AMERICA | BLM21PG300SN1D | N | PWA BOM |  |
| 16 | L31 | 1 | 720101L00-015-G | FB,600 Ohm@100MHz,+/-25%,200mA,500mOhm,G,SMD0603 | MURATA ELEC. NORTH AMERICA | BLM18AG601SN1D | N | PWA BOM |  |
| 17 | R336,R1605,R1700,R1701,R1702,R1703,R1704,R1705,R1706,R1707,R1708,R1709,R1710,R1711,R1712,R1713,R1714,R1715,R1716,R1717,R1718,R1719,R1720,R1721,R1722,R1723,R1724,R1725,R1726,R1727,R1728,R1729,R1730,R1731,R1732,R1733,R1734,R1735,R1736,R1737,R1738,R1739,R1831,R1832,R1834,R1835,R1837,R1838,R1840,R1841,R1843,R1844,R1846,R1847,R1849,R1850,R1852,R1853,R1855,R1856,R1858,R1859,R1861,R1862,R1864,R1865,R1867,R1868,R1870,R1871,R1873,R1874,R1876,R1877,R1879,R1880,R1882,R1883,R1885,R1886,R2065 | 81 | 61010LA00-017-G | RES,4.7KOhm,+/-1%,1/16W,G,SMD0402 | KOA SPEER ELECTRONICS, INC. | RK73H1ETTP4701F | N | PWA BOM |  |
|  |  |  | 61010LA00-012-G | RES,4.7KOhm,+/-1%,1/16W,G,SMD0402 | WALSIN | WR04X4701FTL |  | PWA BOM |  |
|  |  |  | 61010LA00-011-G | RES,4.7KOhm,+/-1%,1/16W,G,SMD0402 | YAGEO | RC0402FR-074K7L |  | PWA BOM |  |
|  |  |  | 61010LA00-044-G | RES,4.7KOhm,+/-1%,1/16W,G,SMD0402 | TA-I | RM04FTN4701 |  | PWA BOM |  |
| 18 | R60,R65,R568,R569,R570,R571,R1888,R1889,R1890,R1891,R1892,R1893,R1894,R1895,R1896,R1897,R1898,R1899,R1900,R1901,R1902,R1903,R1988,R1989,R1990,R1991,R1992,R1993,R1994,R1995,R1996,R1997,R1998,R1999,R2000,R2001,R2002,R2003,R2004,R2005,R2006,R2007,R2008,R2009,R2010,R2011,R2012,R2013,R2014,R2015,R2016,R2017,R2018,R2019,R2020,R2021,R2022,R2023,R2024,R2025,R2026,R2027,R2028,R2029,R2030,R2031,R2032,R2033,R2034,R2035,R2036,R2037,R2038,R2039,R2040,R2041,R2042,R2043,R2044,R2045,R2046,R2047,R2061,R2066,R2067,R2068,R2069,R2070 | 88 | 610107A00-017-G | RES,0 Ohm,+/-5%,1/16W,G,SMD0402 | KOA SPEER ELECTRONICS, INC. | RK73Z1ETTP | N | PWA BOM |  |
|  |  |  | 610107A00-012-G | RES,0 Ohm,+/-5%,1/16W,G,SMD0402 | WALSIN | WR04X000PTL |  | PWA BOM |  |
|  |  |  | 610107A00-011-G | RES,0 Ohm,+/-5%,1/16W,G,SMD0402 | YAGEO | RC0402JR-070RL |  | PWA BOM |  |
|  |  |  | 610107A00-044-G | RES,0 Ohm,+/-5%,1/16W,G,SMD0402 | TA-I | RM04JTN0 |  | PWA BOM |  |
|  |  |  | 610107A00-024-G | RES,0 Ohm,+/-5%,1/16W,G,SMD0402 | PANASONIC INDUSTRIAL CO.,LTD. | ERJ2GE0R00X |  | PWA BOM |  |
|  |  |  | 610107A00-029-G | RES,0 Ohm,+/-5%,1/16W,G,SMD0402 | VISHAY ENTER TECHNO LOGY.INC | CRCW04020000Z0ED |  | PWA BOM |  |
| 19 | R338,R550,R552,R868,R869,R1833,R1836,R1839,R1842,R1845,R1848,R1851,R1854,R1857,R1860,R1863,R1866,R1869,R1872,R1875,R1878,R1881,R1884,R1887 | 24 | 61011H500-017-G | RES,22 Ohm,+/-1%,1/16W,G,SMD0402 | KOA SPEER ELECTRONICS, INC. | RK73H1ETTP22R0F | N | PWA BOM |  |
|  |  |  | 61011H500-012-G | RES,22 Ohm,+/-1%,1/16W,G,SMD0402 | WALSIN | WR04X22R0FTL |  | PWA BOM |  |
|  |  |  | 61011H500-011-G | RES,22 Ohm,+/-1%,1/16W,G,SMD0402 | YAGEO | RC0402FR-0722RL |  | PWA BOM |  |
|  |  |  | 61011H500-044-G | RES,22 Ohm,+/-1%,1/16W,G,SMD0402 | TA-I | RM04FTN22R0 |  | PWA BOM |  |
|  |  |  | 61011H500-024-G | RES,22 Ohm,+/-1%,1/16W,G,SMD0402 | PANASONIC INDUSTRIAL CO.,LTD. | ERJ2RKF22R0X |  | PWA BOM |  |
| 20 | R50,R51,R52,R53,R62,R96,R97,R546,R547,R548,R549,R553,R555,R556,R557,R559,R560,R866,R1078,R1079,R1569,R1570,R1571,R1572,R1573,R1574,R1575,R1576,R1577,R1578,R1579,R1580,R1581,R1582,R1583,R1584,R1585,R1586,R1587,R1588,R1589,R1590,R1591,R1592,R1593,R1594,R1595,R1596,R1597,R1598,R1599,R1600,R1601,R1602,R1603,R1668,R1681,R1684,R1688,R1694,R1697,R1783 | 62 | 610107B00-017-G | RES,4.7KOhm,+/-5%,1/16W,G,SMD0402 | KOA SPEER ELECTRONICS, INC. | RK73B1ETTP472J | N | PWA BOM |  |
|  |  |  | 610107B00-012-G | RES,4.7KOhm,+/-5%,1/16W,G,SMD0402 | WALSIN | WR04X472JTL |  | PWA BOM |  |
|  |  |  | 610107B00-011-G | RES,4.7KOhm,+/-5%,1/16W,G,SMD0402 | YAGEO | RC0402JR-074K7L |  | PWA BOM |  |
|  |  |  | 610107B00-044-G | RES,4.7KOhm,+/-5%,1/16W,G,SMD0402 | TA-I | RM04JTN472 |  | PWA BOM |  |
|  |  |  | 610107B00-024-G | RES,4.7KOhm,+/-5%,1/16W,G,SMD0402 | PANASONIC INDUSTRIAL CO.,LTD. | ERJ2GEJ472X |  | PWA BOM |  |
|  |  |  | 610107B00-029-G | RES,4.7KOhm,+/-5%,1/16W,G,SMD0402 | VISHAY ENTER TECHNO LOGY.INC | CRCW04024K70JNED |  | PWA BOM |  |
| 21 | R1672,R1673,R1679,R1683,R1687,R1698,R1780,R1782 | 8 | 61010JY00-017-G | RES,220 Ohm,+/-5%,1/16W,G,SMD0402 | KOA SPEER ELECTRONICS, INC. | RK73B1ETTP221J | N | PWA BOM |  |
|  |  |  | 61010JY00-012-G | RES,220 Ohm,+/-5%,1/16W,G,SMD0402 | WALSIN | WR04X221JTL |  | PWA BOM |  |
|  |  |  | 61010JY00-011-G | RES,220 Ohm,+/-5%,1/16W,G,SMD0402 | YAGEO | RC0402JR-07220RL |  | PWA BOM |  |
|  |  |  | 61010JY00-044-G | RES,220 Ohm,+/-5%,1/16W,G,SMD0402 | TA-I | RM04JTN221 |  | PWA BOM |  |
| 22 | R106,R1740,R1741,R1742,R1743,R1744,R1745,R1746,R1747,R1748,R1749,R1750,R1751,R1752,R1753,R1754,R1755,R1756,R1757,R1758,R1759,R1760,R1761,R1762,R1763,R1764,R1765,R1766,R1767,R1768,R1769,R1770,R1771,R1772,R1773,R1774,R1775,R1776,R1777,R1778 | 40 | 610101V00-017-G | RES,22 Ohm,+/-5%,1/16W,G,SMD0402 | KOA SPEER ELECTRONICS, INC. | RK73B1ETTP220J | N | PWA BOM |  |
|  |  |  | 610101V00-012-G | RES,22 Ohm,+/-5%,1/16W,G,SMD0402 | WALSIN | WR04X220JTL |  | PWA BOM |  |
|  |  |  | 610101V00-011-G | RES,22 Ohm,+/-5%,1/16W,G,SMD0402 | YAGEO | RC0402JR-0722RL |  | PWA BOM |  |
|  |  |  | 610101V00-044-G | RES,22 Ohm,+/-5%,1/16W,G,SMD0402 | TA-I | RM04JTN220 |  | PWA BOM |  |
|  |  |  | 610101V00-024-G | RES,22 Ohm,+/-5%,1/16W,G,SMD0402 | PANASONIC INDUSTRIAL CO.,LTD. | ERJ2GEJ220X |  | PWA BOM |  |
| 23 | R315 | 1 | 610115J00-017-G | RES,33 Ohm,+/-1%,1/16W,G,SMD0402 | KOA SPEER ELECTRONICS, INC. | RK73H1ETTP33R0F | N | PWA BOM |  |
|  |  |  | 610115J00-012-G | RES,33 Ohm,+/-1%,1/16W,G,SMD0402 | WALSIN | WR04X33R0FTL |  | PWA BOM |  |
|  |  |  | 610115J00-011-G | RES,33 Ohm,+/-1%,1/16W,G,SMD0402 | YAGEO | RC0402FR-0733RL |  | PWA BOM |  |
|  |  |  | 610115J00-044-G | RES,33 Ohm,+/-1%,1/16W,G,SMD0402 | TA-I | RM04FTN33R0 |  | PWA BOM |  |
|  |  |  | 610115J00-024-G | RES,33 Ohm,+/-1%,1/16W,G,SMD0402 | PANASONIC INDUSTRIAL CO.,LTD. | ERJ2RKF33R0X |  | PWA BOM |  |
| 24 | R348,R1522,R1523,R1524,R1525,R1526,R1527,R1528,R1529,R1530,R1531,R1532,R1533,R1534,R1535,R1536,R1537,R1538,R1539,R1540,R1541,R1542,R1543,R1544,R1545,R1546,R1547,R1548,R1549,R1550,R1551,R1552,R1553,R1554,R1555,R1556,R1557,R1558,R1559,R1560,R1561,R1562,R1563,R1564,R1565,R1566,R1567,R1568 | 48 | 61100LQ00-017-G | RES,20KOhm,+/-1%,1/16W,G,SMD0402 | KOA SPEER ELECTRONICS, INC. | RN731ETTP2002F50 |  | PWA BOM |  |
|  |  |  | 61100LQ00-012-G | RES,20KOhm,+/-1%,1/16W,G,SMD0402 | WALSIN | WF04T2002FTL |  | PWA BOM |  |
|  |  |  | 61100LQ00-011-G | RES,20KOhm,+/-1%,1/16W,G,SMD0402 | YAGEO | RT0402FRE0720KL |  | PWA BOM |  |
|  |  |  | 61100LQ00-044-G | RES,20KOhm,+/-1%,1/16W,G,SMD0402 | TA-I | RB04FTS2002 |  | PWA BOM |  |
| 25 | R544,R545 | 2 | 610114J00-017-G | RES,2KOhm,+/-1%,1/16W,G,SMD0402 | KOA SPEER ELECTRONICS, INC. | RK73H1ETTP2001F | N | PWA BOM |  |
|  |  |  | 610114J00-012-G | RES,2KOhm,+/-1%,1/16W,G,SMD0402 | WALSIN | WR04X2001FTL |  | PWA BOM |  |
|  |  |  | 610114J00-011-G | RES,2KOhm,+/-1%,1/16W,G,SMD0402 | YAGEO | RC0402FR-072KL |  | PWA BOM |  |
|  |  |  | 610114J00-044-G | RES,2KOhm,+/-1%,1/16W,G,SMD0402 | TA-I | RM04FTN2001 |  | PWA BOM |  |
|  |  |  | 610114J00-024-G | RES,2KOhm,+/-1%,1/16W,G,SMD0402 | PANASONIC INDUSTRIAL CO.,LTD. | ERJ2RKF2001X |  | PWA BOM |  |
|  |  |  | 610114J00-029-G | RES,2KOhm,+/-1%,1/16W,G,SMD0402 | VISHAY ENTER TECHNO LOGY.INC | CRCW04022K00FKED |  | PWA BOM |  |
| 26 | R558,R561,R562,R564,R565,R566,R567,R2052,R2082 | 9 | 610100T00-017-G | RES,1KOhm,+/-5%,1/16W,G,SMD0402 | KOA SPEER ELECTRONICS, INC. | RK73B1ETTP102J | N | PWA BOM |  |
|  |  |  | 610100T00-012-G | RES,1KOhm,+/-5%,1/16W,G,SMD0402 | WALSIN | WR04X102JTL |  | PWA BOM |  |
|  |  |  | 610100T00-011-G | RES,1KOhm,+/-5%,1/16W,G,SMD0402 | YAGEO | RC0402JR-071KL |  | PWA BOM |  |
|  |  |  | 610100T00-044-G | RES,1KOhm,+/-5%,1/16W,G,SMD0402 | TA-I | RM04JTN102 |  | PWA BOM |  |
|  |  |  | 610100T00-024-G | RES,1KOhm,+/-5%,1/16W,G,SMD0402 | PANASONIC INDUSTRIAL CO.,LTD. | ERJ2GEJ102X |  | PWA BOM |  |
| 27 | R865,R1072,R1073,R1074,R1077,R1438,R1439,R1440 | 8 | 61010L300-017-G | RES,1KOhm,+/-1%,1/16W,G,SMD0402 | KOA SPEER ELECTRONICS, INC. | RK73H1ETTP1001F | N | PWA BOM |  |
|  |  |  | 61010L300-012-G | RES,1KOhm,+/-1%,1/16W,G,SMD0402 | WALSIN | WR04X1001FTL |  | PWA BOM |  |
|  |  |  | 61010L300-011-G | RES,1KOhm,+/-1%,1/16W,G,SMD0402 | YAGEO | RC0402FR-071KL |  | PWA BOM |  |
|  |  |  | 61010L300-044-G | RES,1KOhm,+/-1%,1/16W,G,SMD0402 | TA-I | RM04FTN1001 |  | PWA BOM |  |
|  |  |  | 61010L300-024-G | RES,1KOhm,+/-1%,1/16W,G,SMD0402 | PANASONIC INDUSTRIAL CO.,LTD. | ERJ2RKF1001X |  | PWA BOM |  |
|  |  |  | 61010L300-029-G | RES,1KOhm,+/-1%,1/16W,G,SMD0402 | VISHAY ENTER TECHNO LOGY.INC | CRCW04021K00FKED |  | PWA BOM |  |
| 28 | R583 | 1 | 61011BQ00-017-G | RES,2.2 Ohm,+/-5%,1/16W,G,SMD0402 | KOA SPEER ELECTRONICS, INC. | RK73B1ETTP2R2J | N | PWA BOM |  |
|  |  |  | 61011BQ00-011-G | RES,2.2 Ohm,+/-5%,1/16W,G,SMD0402 | YAGEO CORPORATION COMPONENT | RC0402JR-072R2L |  | PWA BOM |  |
|  |  |  | 61011BQ00-012-G | RES,2.2 Ohm,+/-5%,1/16W,G,SMD0402 | WALSIN TECHNOLOGY CORPORATION | WR04X2R2JTL |  | PWA BOM |  |
|  |  |  | 61011BQ00-044-G | RES,2.2 Ohm,+/-5%,1/16W,G,SMD0402 | TA-I TECHNOLOGY CO., LTD | RM04JTN2R2 |  | PWA BOM |  |
| 29 | R585 | 1 | 610108300-017-G | RES,0 Ohm,+/-5%,1/10W,G,SMD0603 | KOA SPEER ELECTRONICS, INC. | RK73Z1JTTD | N | PWA BOM |  |
|  |  |  | 610108300-012-G | RES,0 Ohm,+/-5%,1/10W,G,SMD0603 | WALSIN | WR06X000PTL |  | PWA BOM |  |
|  |  |  | 610108300-011-G | RES,0 Ohm,+/-5%,1/10W,G,SMD0603 | YAGEO | RC0603JR-070RL |  | PWA BOM |  |
|  |  |  | 610108300-044-G | RES,0 Ohm,+/-5%,1/10W,G,SMD0603 | TA-I | RM06JTN0 |  | PWA BOM |  |
|  |  |  | 610108300-024-G | RES,0 Ohm,+/-5%,1/10W,G,SMD0603 | PANASONIC INDUSTRIAL CO.,LTD. | ERJ3GEY0R00V |  | PWA BOM |  |
| 30 | R817,R818,R828,R830,R832,R833,R834,R860,R867,R1443,R1444,R1445,R1446,R1447,R1448,R1458,R1459,R1460,R1461,R1462,R1463,R1464,R1465,R1466,R1467,R1468,R1469,R1470,R1471,R1472,R1473,R1604 | 32 | 610118400-017-G | RES,27 Ohm,+/-1%,1/16W,G,SMD0402 | KOA SPEER ELECTRONICS, INC. | RK73H1ETTP27R0F | N | PWA BOM |  |
|  |  |  | 610118400-012-G | RES,27 Ohm,+/-1%,1/16W,G,SMD0402 | WALSIN | WR04X27R0FTL |  | PWA BOM |  |
|  |  |  | 610118400-011-G | RES,27 Ohm,+/-1%,1/16W,G,SMD0402 | YAGEO | RC0402FR-0727RL |  | PWA BOM |  |
|  |  |  | 610118400-044-G | RES,27 Ohm,+/-1%,1/16W,G,SMD0402 | TA-I | RM04FTN27R0 |  | PWA BOM |  |
| 31 | R1785,R1787,R1788,R1791,R1793,R1795,R1796,R1799,R1800,R1803,R1804,R1807,R1808,R1811,R1812,R1815,R1816,R1819,R1820,R1823,R1824,R1827,R1828,R2049,R2050,R2051,R2062,R2063,R2064,R2071,R2075,R2077,R2079,R2083,R2084 | 35 | 61100AH00-017-G | RES,10KOhm,+/-0.5%,1/16W,G,SMD0402 | KOA SPEER ELECTRONICS, INC. | RN731ETTP1002D25 | Y | PWA BOM |  |
|  |  |  | 61100AH00-012-G | RES,10KOhm,+/-0.5%,1/16W,G,SMD0402 | WALSIN | WF04U1002DTL |  | PWA BOM |  |
|  |  |  | 61100AH00-011-G | RES,10KOhm,+/-0.5%,1/16W,G,SMD0402 | YAGEO | RT0402DRE0710KL |  | PWA BOM |  |
|  |  |  | 61100AH00-044-G | RES,10KOhm,+/-0.5%,1/16W,G,SMD0402 | TA-I | RB04DTP1002 |  | PWA BOM |  |
| 32 | R1786,R1789,R1790,R1792,R1794,R1797,R1798,R1801,R1802,R1805,R1806,R1809,R1810,R1813,R1814,R1817,R1818,R1821,R1822,R1825,R1826,R1829,R1830 | 23 | 61010FG00-017-G | RES,20KOhm,+/-5%,1/16W,G,SMD0402 | KOA SPEER ELECTRONICS, INC. | RK73B1ETTP203J | N | PWA BOM |  |
|  |  |  | 61010FG00-012-G | RES,20KOhm,+/-5%,1/16W,G,SMD0402 | WALSIN TECHNOLOGY CORPORATION | WR04X203JTL | G | PWA BOM |  |
|  |  |  | 61010FG00-011-G | RES,20KOhm,+/-5%,1/16W,G,SMD0402 | YAGEO CORPORATION COMPONENT | RC0402JR-0720KL | G | PWA BOM |  |
| 33 | R1408,R1449 | 2 | 610107L00-017-G | RES,1 Ohm,+/-5%,1/10W,G,SMD0603 | KOA SPEER ELECTRONICS, INC. | RK73B1JTTD1R0J | N | PWA BOM |  |
| 34 | R2060 | 1 | 610154800-017-G | RES,1 Ohm,+/-5%,1/8W,G,SMD0402 | KOA SPEER ELECTRONICS, INC. | SG73P1ETTP1R0J |  | PWA BOM |  |
| 35 | U_Clock_B,U_Clock_A | 2 | 21050LL00-217-G | IC,IDT,9ZXL0831AKLFT,G,VFQFPN-48,SMD | INTEGRATED DEVICE TECHNOLOGY | 9ZXL0831AKLFT |  | PWA BOM |  |
| 36 | U_MUX1,U_MUX2,U_MUX3,U_MUX4,U_MUX5 | 5 | 31030CA00-031-G | IC,Switch,PCA9546APW,2.3~5.5V,G,TSSOP-16,SMD | NXP SEMICONDUCTORS | PCA9546APW | N | PWA BOM |  |
|  |  |  | 31030YF00-252-G | Logic IC,Switch,PI4MSD5V9546ALEX,1.65V~5.5V,0.3ns,TSSOP,16P,G | PERICOM SEMICONDUCTOR CORP | PI4MSD5V9546ALEX | G | PWA BOM |  |
| 37 | U_RESET | 1 | 32040P400-399-G | IC,Voltage sensor,SLG4N020VTR,G,TDFN-8,SMD | SILEGO | SLG4N020VTR |  | PWA BOM |  |
| 38 | U_SF2 | 1 | 21081NC00-432-G | IC,LSI,500021009,A2,G,TFBGA-141,SMD | LSI LOGIC CORPORATION | 500021009 |  | PWA BOM |  |
| 39 | U209,U229,U230,U231,U232,U233,U234,U235,U236,U237,U238,U239,U240,U241,U242,U243,U244,U245,U246,U247 | 20 | 310501200-183-G | IC,Buffer,SN74LVC1G07DCKR,1.65~5.5V,G,SC70-5,SMD | TEXAS INSTRUMENTS | SN74LVC1G07DCKR | N | PWA BOM |  |
| 40 | U248 | 1 | 220107K00-413-G | IC,PLD,10M02SCU169C8G,116MHz,3.3V,G,UBGA-169,SMD | ALTERA CORPORATION | 10M02SCU169C8G |  | PWA BOM |  |
| 41 | X7 | 1 | 71012HD00-100-G | XTAL,25MHz,+/-20ppm,8pF,G,SMD | TXC CORPORATION | 7V25000054 |  | PWA BOM |  |
| 42 | Y3 | 1 | 71020SH00-107-G | OSC,25MHz,+/-25ppm,3.3V,15pF,G,SMD | DAISHINKU CORPORATION/DAISHINKU SINGAPORE PTE LTD/KDS | 1XSE025000AR122 |  | PWA BOM |  |
| 43 | JPCIE1,JPCIE2,JPCIE3,JPCIE4,JPCIE5,JPCIE6,JPCIE7 | 7 | 340718900-245-G | CONN,SAS,V/T,0.6mm,30u,G,SMD-74 | AMPHENOL SHANGHAI CORP. | U10-B074-260T |  | PWA BOM |  |
| 44 | J_CPLD_JTAG | 1 | 3406B0G00-309-G | CONN,Header,Pin Header,2X5,V/T,Bla,2.54mm,10u,G,SMD-10 | SAMTEC INC. | TSM-105-04-L-DV-A-P-TR |  | PWA BOM |  |
| 45 | J_NVME01,J_NVME02,J_NVME03,J_NVME04,J_NVME05,J_NVME06,J_NVME07,J_NVME08,J_NVME09,J_NVME10,J_NVME11,J_NVME12,J_NVME13,J_NVME14,J_NVME15,J_NVME16,J_NVME17,J_NVME18,J_NVME19,J_NVME20,J_NVME21,J_NVME22,J_NVME23,J_NVME00 | 24 | 340313H00-600-G | CONN,PCIE,V/T,Bla,0.8mm,30u,G,SMD-68 | FOXCONN TECHNOLOGY CO.,LTD. | LU25683-A001-9H |  | PWA BOM |  |
| 46 | J1 | 1 | 3406B3H00-317-G | CONN,Header,Power,2X8,V/T,Bla,3mm,G,SMD-16 | MOLEX INCORPORATED | 43045-1618 | N | PWA BOM |  |
| ##### Remove Parts |  |  |  |  |  |  |  |  |  |
| Item | Location | Qty | Foxconn P/N | Part Description | Manufacturer Full Name | Manufacturer P/N | RoHS | Sheet |  |
| 1 | C225,C226,C227,C228,C229,C230,C231,C232,C233,C234,C235,C236,C237,C238,C239,C240,C241,C242,C243,C244,C245,C246,C247,C248 | 24 | 620101T02-015-G | CAP,100nF,+/-10%,X7R,16V,G,SMD0402 | MURATA ELEC. NORTH AMERICA | GRM155R71C104K | Y | PWA BOM |  |
|  |  |  | 620101T00-012-G | CAP,100nF,+/-10%,X7R,16V,G,SMD0402 | WALSIN | 0402B104K160CT |  | PWA BOM |  |
|  |  |  | 620101T00-026-G | CAP,100nF,+/-10%,X7R,16V,G,SMD0402 | SAMSUNG SEMICONDUCTOR | CL05B104KO5NNNC |  | PWA BOM |  |
|  |  |  | 620101T00-015-G | CAP,100nF,+/-10%,X7R,16V,G,SMD0402 | MURATA ELEC. NORTH AMERICA | GRM155R71C104KA88D |  | PWA BOM |  |
| 2 | PSRR8,R316,R325,R405,R421,R437,R453,R469,R485,R611,R627,R643,R659,R675,R691,R707,R723,R739,R755,R771,R787,R803,R819,R835,R851 | 25 | 610107A00-017-G | RES,0 Ohm,+/-5%,1/16W,G,SMD0402 | KOA SPEER ELECTRONICS, INC. | RK73Z1ETTP | N | PWA BOM |  |
|  |  |  | 610107A00-012-G | RES,0 Ohm,+/-5%,1/16W,G,SMD0402 | WALSIN | WR04X000PTL |  | PWA BOM |  |
|  |  |  | 610107A00-011-G | RES,0 Ohm,+/-5%,1/16W,G,SMD0402 | YAGEO | RC0402JR-070RL |  | PWA BOM |  |
|  |  |  | 610107A00-044-G | RES,0 Ohm,+/-5%,1/16W,G,SMD0402 | TA-I | RM04JTN0 |  | PWA BOM |  |
|  |  |  | 610107A00-024-G | RES,0 Ohm,+/-5%,1/16W,G,SMD0402 | PANASONIC INDUSTRIAL CO.,LTD. | ERJ2GE0R00X |  | PWA BOM |  |
|  |  |  | 610107A00-029-G | RES,0 Ohm,+/-5%,1/16W,G,SMD0402 | VISHAY ENTER TECHNO LOGY.INC | CRCW04020000Z0ED |  | PWA BOM |  |
| 3 | Q1,Q2,Q3,Q4,Q5,Q6,Q7,Q8,Q9,Q10,Q11,Q12,Q13,Q14,Q15,Q16,Q17,Q18,Q19,Q20,Q21,Q22,Q23,Q24 | 24 | 510301D00-223-G | MOS N,BSS138LT1G,50V,0.2A,3.5ohm@5V,G,SOT23-3,SMD | ON SEMICONDUCTOR CORP | BSS138LT1G | N | PWA BOM |  |
|  |  |  | 510309C00-237-G | MOS N,BSS138-7-F,50V,0.2A,3.5ohm@10V,G,SOT23-3,SMD | DIODES INCORPORATION | BSS138-7-F |  | PWA BOM |  |
|  |  |  | 510302R00-185-G | MOS N,BSS138,50V,0.22A,6ohm@4.5V,G,SOT23-3,SMD | FAIRCHILD SEMICONDUCTOR CORP | BSS138 |  | PWA BOM |  |
|  |  |  | 51030A800-221-G | MOS N,BSS138N,60V,0.23A,6ohm@4.5V,G,SOT23-3,SMD | INFINEON TECHNOLOGIES CORP. | BSS138N |  | PWA BOM |  |
| 4 | R322,R328,R408,R424,R440,R456,R472,R488,R587,R588,R589,R590,R591,R592,R593,R594,R595,R596,R597,R598,R599,R600,R601,R602,R603,R604,R605,R606,R607,R608,R609,R610,R614,R630,R646,R662,R678,R694,R710,R726,R742,R758,R774,R790,R806,R822,R838,R854 | 48 | 610107B00-017-G | RES,4.7KOhm,+/-5%,1/16W,G,SMD0402 | KOA SPEER ELECTRONICS, INC. | RK73B1ETTP472J | N | PWA BOM |  |
|  |  |  | 610107B00-012-G | RES,4.7KOhm,+/-5%,1/16W,G,SMD0402 | WALSIN | WR04X472JTL |  | PWA BOM |  |
|  |  |  | 610107B00-011-G | RES,4.7KOhm,+/-5%,1/16W,G,SMD0402 | YAGEO | RC0402JR-074K7L |  | PWA BOM |  |
|  |  |  | 610107B00-044-G | RES,4.7KOhm,+/-5%,1/16W,G,SMD0402 | TA-I | RM04JTN472 |  | PWA BOM |  |
|  |  |  | 610107B00-024-G | RES,4.7KOhm,+/-5%,1/16W,G,SMD0402 | PANASONIC INDUSTRIAL CO.,LTD. | ERJ2GEJ472X |  | PWA BOM |  |
|  |  |  | 610107B00-029-G | RES,4.7KOhm,+/-5%,1/16W,G,SMD0402 | VISHAY ENTER TECHNO LOGY.INC | CRCW04024K70JNED |  | PWA BOM |  |
| 5 | R870,R871,R872,R873,R922,R923,R924,R925,R926,R927,R928,R929,R930,R931 | 14 | 61011H100-017-G | RES,220 Ohm,+/-1%,1/16W,G,SMD0402 | KOA SPEER ELECTRONICS, INC. | RK73H1ETTP2200F | N | PWA BOM |  |
|  |  |  | 61011H100-012-G | RES,220 Ohm,+/-1%,1/16W,G,SMD0402 | WALSIN | WR04X2200FTL |  | PWA BOM |  |
|  |  |  | 61011H100-011-G | RES,220 Ohm,+/-1%,1/16W,G,SMD0402 | YAGEO | RC0402FR-07220RL |  | PWA BOM |  |
|  |  |  | 61011H100-044-G | RES,220 Ohm,+/-1%,1/16W,G,SMD0402 | TA-I | RM04FTN2200 |  | PWA BOM |  |
|  |  |  | 61011H100-024-G | RES,220 Ohm,+/-1%,1/16W,G,SMD0402 | PANASONIC INDUSTRIAL CO.,LTD. | ERJ2RKF2200X |  | PWA BOM |  |
|  |  |  | 61011H100-029-G | RES,220 Ohm,+/-1%,1/16W,G,SMD0402 | VISHAY ENTER TECHNO LOGY.INC | CRCW0402220RFKEDC |  | PWA BOM |  |
| 6 | U5,U6,U7,U8,U9,U10,U11,U12,U13,U14,U15,U16,U17,U18,U19,U20,U21,U22,U23,U24,U25,U26,U27,U28 | 24 | 310102400-183-G | IC,Gate&Inverter,SN74AHC1G32DBVR,2~5.5V,G,SOT23-5,SMD | TEXAS INSTRUMENTS | SN74AHC1G32DBVR | N | PWA BOM |  |
|  |  |  | 310106R00-185-G | IC,Gate&Inverter,NC7S32M5X,2~6V,G,SOT23-5,SMD | FAIRCHILD SEMICONDUCTOR CORP | NC7S32M5X |  | PWA BOM |  |
|  |  |  | 310106U00-031-G | IC,Gate&Inverter,74AHC1G32GV,2~5.5V,G,SC74A-5,SMD | NXP SEMICONDUCTORS | 74AHC1G32GV |  | PWA BOM |  |
| 7 | U30,U31,U32 | 3 | 21050LL00-217-G | IC,IDT,9ZXL0831AKLFT,G,VFQFPN-48,SMD | INTEGRATED DEVICE TECHNOLOGY | 9ZXL0831AKLFT |  | PWA BOM |  |
| 8 | J_BP_PWR1 | 1 | 3406B3H00-317-G | CONN,Header,Power,2X8,V/T,Bla,3mm,G,SMD-16 | MOLEX INCORPORATED | 43045-1618 | N | PWA BOM |  |
| 9 | H1,H2,H3,H4,H7,H8,H9,H10 | 8 | 2A5910Q00-HYM-G | SMT NUT,CARBON STEEL,G,FIVETECH,82-059-01-022-01-RL | Fivetech Technology Inc. | 82-059-01-022-01-RL |  | PWA BOM |  |
|  |  |  | 2A5914300-G44-G | 螺母,Nut,CARBON STEEL,N/A,4.7,3.5,7,TIN Plating,圓柱,G,00 | PennEngineering Fastening | YSMTSO-47670-ET |  | PWA BOM |  |
| 10 | JNVME_AUX1,JNVME_AUX2,JNVME_AUX3,JNVME_AUX4,JNVME_AUX5,JNVME_AUX6,JNVME_AUX7 | 7 | 340718900-245-G | CONN,SAS,V/T,0.6mm,30u,G,SMD-74 | AMPHENOL SHANGHAI CORP. | U10-B074-260T |  | PWA BOM |  |
| 11 | J_COMBODRV1,J_COMBODRV2,J_COMBODRV3,J_COMBODRV4,J_COMBODRV5,J_COMBODRV6,J_COMBODRV7,J_COMBODRV8,J_COMBODRV9,J_COMBODRV10,J_COMBODRV11,J_COMBODRV12,J_COMBODRV13,J_COMBODRV14,J_COMBODRV15,J_COMBODRV16,J_COMBODRV17,J_COMBODRV18,J_COMBODRV19,J_COMBODRV20,J_COMBODRV21,J_COMBODRV22,J_COMBODRV23,J_COMBODRV0 | 24 | 340313H00-600-G | CONN,PCIE,V/T,Bla,0.8mm,30u,G,SMD-68 | FOXCONN TECHNOLOGY CO.,LTD. | LU25683-A001-9H |  | PWA BOM |  |
| ##### Change Parts |  |  |  |  |  |  |  |  |  |
| Item | Location | Qty | Foxconn P/N | Part Description | Manufacturer Full Name | Manufacturer P/N | RoHS | Sheet | Remark |
| 1 | CE1 | 1 | 62111EC00-021-G | ECAP,680uF,+/-20%,16V,105℃,G,SMD10*10,ESR<=80mOhm | NIPPON CHEMI-CON CORPORATION | EMZA160ADA681MJA0G |  | PWA BOM | In New BOM |
|  |  |  | 62110EH00-024-G | ECAP,680uF,+/-20%,16V,105_x0003_,G,SMD10X10.2,ESR<=80mOhm | PANASONIC INDUSTRIAL CO.,LTD. | EEEFK1C681P |  | PWA BOM | In New BOM |
|  |  |  | 62111H200-018-G | ECAP,680uF,+/-20%,16V,105_x0003_,G,SMD10X10.5,ESR<=80mOhm | RUBYCON CORP. | 16TZV680M10X10.5 |  | PWA BOM | In New BOM |
|  | CE1 | 1 | 62111EC00-021-G | ECAP,680uF,+/-20%,16V,105℃,G,SMD10*10,ESR<=80mOhm | NIPPON CHEMI-CON CORPORATION | EMZA160ADA681MJA0G |  | PWA BOM | In Old BOM |
|  |  |  | 62110EH00-024-G | ECAP,680uF,+/-20%,16V,105℃,G,SMD10X10.2,ESR<=80mOhm | PANASONIC INDUSTRIAL CO.,LTD. | EEEFK1C681P |  | PWA BOM | In Old BOM |
|  |  |  | 62111H200-018-G | ECAP,680uF,+/-20%,16V,105℃,G,SMD10X10.5,ESR<=80mOhm | RUBYCON CORP. | 16TZV680M10X10.5 |  | PWA BOM | In Old BOM |
| 2 | LED37,LED39,LED49,LED51,LED53,LED55,LED57,LED59,LED61,LED63,LED65,LED67,LED69,LED71,LED73,LED75,LED77,LED79,LED81,LED83,LED85,LED87,LED89,LED91 | 24 | 52110LN00-289-G | LED,Gre,LTST-C191KGKT,2.4V,30mA,G,SMD0603 | LITE-ON TECHNOLOGY CORPORATION | LTST-C191KGKT |  | PWA BOM | In New BOM |
|  |  |  | 52110K100-030-G | LED LAMP,SML-512MWT86,Green,40mcd@If=20mA,N/A,5V,25mA,N/A,,SMD0603,2P,G | ROHM CORPORATION | SML-512MWT86 | G | PWA BOM | In New BOM |
|  | LED37,LED39,LED49,LED51,LED53,LED55,LED57,LED59,LED61,LED63,LED65,LED67,LED69,LED71,LED73,LED75,LED77,LED79,LED81,LED83,LED85,LED87,LED89,LED91 | 24 | 52110LN00-289-G | LED,Gre,LTST-C191KGKT,2.4V,30mA,G,SMD0603 | LITE-ON TECHNOLOGY CORPORATION | LTST-C191KGKT |  | PWA BOM | In Old BOM |
|  |  |  | 52110K100-030-G | LED LAMP,SML-512MWT86,Green,40mcd@If=20mA,N/A,5V,25mA,N/A,,SMD0603,2P,G | ROHM CORPORATION | SML-512MWT86 |  | PWA BOM | In Old BOM |
| 3 | L1 | 1 | 720101900-015-G | FB,60 Ohm@100MHz,+/-25%,3A,25mOhm,G,SMD0805 | MURATA ELEC. NORTH AMERICA | BLM21PG600SN1D | N | PWA BOM | In New BOM |
|  |  |  | 720101900-026-G | FB,60 Ohm@100MHz,+/-25%,3A,25mOhm,G,SMD0805 | SAMSUNG | CIC21P600NE | G | PWA BOM | In New BOM |
|  | L1 | 1 | 720101900-015-G | FB,60 Ohm@100MHz,+/-25%,3A,25mOhm,G,SMD0805 | MURATA ELEC. NORTH AMERICA | BLM21PG600SN1D | N | PWA BOM | In Old BOM |
|  |  |  | 720102E00-129-G | FB,60 Ohm@100MHz,+/-25%,3A,40mOhm,G,SMD0805 | MAG.LAYERS, SCIENTIFIC-TECHNICS (KUNSHAN) CO., LTD. | GMLB-201209-0060P-N8 |  | PWA BOM | In Old BOM |
|  |  |  | 720104100-074-G | FB,60 Ohm@100MHz,+/-25%,3A,30mOhm,G,SMD0805 | CHILISIN ELECTRONICS CORP. | PBY201209T-600Y-N |  | PWA BOM | In Old BOM |
| 4 | PSRC2,PSTC6,PFTC6,PETC6,PSTC7,PFTC7,PETC7,PSTC8,PFTC8,PETC8,PSTC9,PFTC9,PETC9,PSRC17,PSTC3005,PFTC3005,PETC3005,PSTC3006,PFTC3006,PETC3006,PSTC3007,PFTC3007,PETC3007,PSTC3010,PFTC3010,PETC3010,PSTC3011,PFTC3011,PETC3011,PSTC3012,PFTC3012,PETC3012,PSTC3013,PFTC3013,PETC3013,PFTC3014,PETC3014,PFTC3015,PETC3015,PFTC3016,PETC3016 | 41 | 62012T500-015-G | CAP,22uF,+/-20%,X7S,25V,G,SMD1206 | MURATA ELEC. NORTH AMERICA | GRM31CC71E226ME11L |  | PWA BOM | In New BOM |
|  | PSRC2,PSTC6,PFTC6,PETC6,PSTC7,PFTC7,PETC7,PSTC8,PFTC8,PETC8,PSTC9,PFTC9,PETC9,PSRC17,PSTC3005,PFTC3005,PETC3005,PSTC3006,PFTC3006,PETC3006,PSTC3007,PFTC3007,PETC3007,PSTC3010,PFTC3010,PETC3010,PSTC3011,PFTC3011,PETC3011,PSTC3012,PFTC3012,PETC3012,PSTC3013,PFTC3013,PETC3013,PFTC3014,PETC3014,PFTC3015,PETC3015,PFTC3016,PETC3016 | 41 | 62012T500-015-G | CAP,22uF,+/-20%,X7S,25V,G,SMD1206 | MURATA ELEC. NORTH AMERICA | GRM31CC71E226ME11L |  | PWA BOM | In Old BOM |
|  |  |  | 62012R900-026-G | CAP,22uF,+/-10%,X6S,25V,G,SMD1206 | SAMSUNG SEMICONDUCTOR | CL31X226KAHN3NE | G | PWA BOM | In Old BOM |
| 5 | PSTL1,PFTL1,PETL1 | 3 | 630335M00-088-G | IND,820nH@100KHz,+/-20%,13A,8mOhm,SHLD,G,SMD | COOPER BUSSMANN, INC. | HCM0703-R82-R |  | PWA BOM | In New BOM |
|  |  |  | 63035Y800-051-G | Coil Ind,Shielded(SHLD),820nH@100KHz,+/-20%,13A,8mOhm,SMD,7.6*6.9*3.0,,,G | PULSE ELECTRONICS (SINGAPORE) | PA4341.821NLT | G | PWA BOM | In New BOM |
|  |  |  | SPS-06CZ-R82M-V1 | Ind,SPS-06CZ-R82M-V1 | MAG.LAYERS, SCIENTIFIC-TECHNICS (KUNSHAN) CO., LTD. | SPS-06CZ-R82M-V1 | G | PWA BOM | In New BOM |
|  | PSTL1,PFTL1,PETL1 | 3 | 630335M00-088-G | IND,820nH@100KHz,+/-20%,13A,8mOhm,SHLD,G,SMD | COOPER BUSSMANN, INC. | HCM0703-R82-R |  | PWA BOM | In Old BOM |
|  |  |  | 63031F600-051-G | IND,820nH@100KHz,+/-20%,13A,8mOhm,SHLD,G,SMD | PULSE | PG0426.821NLT |  | PWA BOM | In Old BOM |
| 6 | PSTL2,PFTL2,PETL2 | 3 | 630341400-088-G | IND,22nH@1MHz,+/-20%,19A,368uOhm,SHLD,G,SMD | COOPER BUSSMANN, INC. | FP0404R1-R022-R |  | PWA BOM | In New BOM |
|  |  |  | HCB0430-220 | IND,HCB0430-220 | Delta | HCB0430-220 | G | PWA BOM | In New BOM |
|  | PSTL2,PFTL2,PETL2 | 3 | 630341400-088-G | IND,22nH@1MHz,+/-20%,19A,368uOhm,SHLD,G,SMD | COOPER BUSSMANN, INC. | FP0404R1-R022-R |  | PWA BOM | In Old BOM |
| 7 | PSRL2 | 1 | 63032PP00-088-G | IND,4.7uH@100KHz,+/-20%,5.5A,40mOhm,SHLD,G,SMD | COOPER BUSSMANN, INC. | HCM0703-4R7-R |  | PWA BOM | In New BOM |
|  |  |  | 63030PW00-034-G | Coil Ind,Shielded(SHLD),4.7uH@100KHz,+/-20%,5.5A,40mOhm,SMD,7.3*6.6*3.0,G | CYNTEC CO. LTD | PCMC063T-4R7MN | G | PWA BOM | In New BOM |
|  |  |  | SPS-06CZ-4R7M-V1 | IND,SPS-06CZ-4R7M-V1 | MAG.LAYERS, SCIENTIFIC-TECHNICS (KUNSHAN) CO., LTD. | SPS-06CZ-4R7M-V1 | G | PWA BOM | In New BOM |
|  | PSRL2 | 1 | 63032PP00-088-G | IND,4.7uH@100KHz,+/-20%,5.5A,40mOhm,SHLD,G,SMD | COOPER BUSSMANN, INC. | HCM0703-4R7-R |  | PWA BOM | In Old BOM |
|  |  |  | 63034RV00-15A-G | IND,4.7uH@100KHz,+/-20%,5.5A,40mOhm,SHLD,G,SMD | ITG | SMHC2511-4R7MHF |  | PWA BOM | In Old BOM |
| 8 | PSRR19 | 1 | 61100YB00-017-G | RES,2.94KOhm,+/-0.1%,1/16W,G,SMD0402 | KOA SPEER ELECTRONICS, INC. | RN731ETTP2941B25 |  | PWA BOM | In New BOM |
|  | PSRR19 | 1 | 61100YB00-017-G | RES,2.94KOhm,+/-0.1%,1/16W,G,SMD0402 | KOA SPEER ELECTRONICS, INC. | RN731ETTP2941B25 |  | PWA BOM | In Old BOM |
|  |  |  | 61100YB00-011-G | RES,2.94KOhm,+/-0.1%,1/16W,G,SMD0402 | YAGEO | RT0402BRD072K94L |  | PWA BOM | In Old BOM |
| 9 | U_AND1,U_AND2 | 2 | 310101400-031-G | IC,Gate&Inverter,74LVC1G08GW,1.65~5.5V,G,SOT353-5,SMD | NXP SEMICONDUCTORS | 74LVC1G08GW | N | PWA BOM | In New BOM |
|  |  |  | 310103J00-223-G | IC,Gate&Inverter,NL17SZ08DFT2G,1.65~5.5V,G,SOT353-5,SMD | ON SEMICONDUCTOR CORP | NL17SZ08DFT2G | G | PWA BOM | In New BOM |
|  |  |  | 31010J400-131-G | IC,Gate&Inverter,TC7SZ08FU,1.8~5.5V,G,SSOP-5,SMD | TOSHIBA ELECTRONICS ASIA LTD | TC7SZ08FU | G | PWA BOM | In New BOM |
|  | U_AND1,U_AND2 | 2 | 310101400-031-G | IC,Gate&Inverter,74LVC1G08GW,1.65~5.5V,G,SOT353-5,SMD | NXP SEMICONDUCTORS | 74LVC1G08GW | N | PWA BOM | In Old BOM |
|  |  |  | 310102100-183-G | IC,Gate&Inverter,SN74LVC1G08DCKR,1.65~5.5V,G,SOT323-5,SMD | TEXAS INSTRUMENTS | SN74LVC1G08DCKR |  | PWA BOM | In Old BOM |
|  |  |  | 310103J00-223-G | IC,Gate&Inverter,NL17SZ08DFT2G,1.65~5.5V,G,SOT353-5,SMD | ON SEMICONDUCTOR CORP | NL17SZ08DFT2G |  | PWA BOM | In Old BOM |
| 10 | U_I2C_RE1 | 1 | 311004800-031-G | IC,Translator,PCA9617ADPJ,0.8~5.5V,2.2~5.5V,G,TSSOP-8,SMD | NXP SEMICONDUCTORS | PCA9617ADPJ |  | PWA BOM | In New BOM |
|  |  |  | 311004V00-223-G | Logic IC,Translator,PCA9617ADMR2G,Vcca=0.8V~5.5V,Vccb=2.2V~5.5V,102ns,Micro8,8P,G | ON SEMICONDUCTOR CORP | PCA9617ADMR2G |  | PWA BOM | In New BOM |
|  | U_I2C_RE1 | 1 | 311004800-031-G | IC,Translator,PCA9617ADPJ,0.8~5.5V,2.2~5.5V,G,TSSOP-8,SMD | NXP SEMICONDUCTORS | PCA9617ADPJ |  | PWA BOM | In Old BOM |
|  |  |  | 311004V00-223-G | Logic IC,Translator,PCA9617ADMR2G,Vcca=0.8V~5.5V,Vccb=2.2V~5.5V,102ns,Micro8,8P,G | ON SEMICONDUCTOR CORP | PCA9617ADMR2G |  | PWA BOM | In Old BOM |
|  |  |  | 311004K00-183-G | Logic IC,Translator,TCA9617ADGKR,Vcca=0.8V~5.5V;Vccb=2.2V~5.5V,250ns,VSSOP,8P,G | TEXAS INSTRUMENTS | TCA9617ADGKR |  | PWA BOM | In Old BOM |
|  |  |  | 311004U00-252-G | Logic IC,Translator,PI6ULS5V9617AUEX,Vcca=0.8V~5.5V,Vccb=2.2V~5.5V,102ns,MSOP,8P,G | PERICOM SEMICONDUCTOR CORP | PI6ULS5V9617AUEX |  | PWA BOM | In Old BOM |
| 11 | U_TMP1 | 1 | 32040J800-183-G | IC,Temp Sensor,TMP75AIDGKR,N/A,G,MSOP-8,SMD | TEXAS INSTRUMENTS | TMP75AIDGKR | N | PWA BOM | In New BOM |
|  |  |  | 32040PJ00-223-G | IC,Temperature Sensor,NCT75DMR2G,G,MSOP-8,SMD | ON SEMICONDUCTOR CORP | NCT75DMR2G |  | PWA BOM | In New BOM |
|  | U_TMP1 | 1 | 32040J800-183-G | IC,Temp Sensor,TMP75AIDGKR,N/A,G,MSOP-8,SMD | TEXAS INSTRUMENTS | TMP75AIDGKR | N | PWA BOM | In Old BOM |
|  |  |  | 32040PJ00-223-G | IC,Temperature Sensor,NCT75DMR2G,G,MSOP-8,SMD | ON SEMICONDUCTOR CORP | NCT75DMR2G |  | PWA BOM | In Old BOM |
| 12 | PCB | 1 | PCB | PCB | PCB | PCB | G | PWA BOM | In New BOM |
|  | PCB | 1 | PCB | PCB | TBD | PCB | G | PWA BOM | In Old BOM |
| 13 | U_BP_FRU1 | 1 | 41040B600-191-G | EEPROM,AT24C02C-SSHM-T,1.7~5.5V,2K,I2C,G,SOIC-8,SMD | ATMEL CORPORATION | FP0404R1-R022-R | N | PWA BOM | In New BOM |
|  | U_BP_FRU1 | 1 | 41040HW00-191-G | EEPROM,AT24C02D-SSHM-T,1.7~3.6V,2K,I2C,G,SOIC-8,SMD | ATMEL CORPORATION | AT24C02D-SSHM-T |  | PWA BOM | In Old BOM |
|  |  |  | 32040PJ00-223-G | IC,Temperature Sensor,NCT75DMR2G,G,MSOP-8,SMD | ON SEMICONDUCTOR CORP | NCT75DMR2G |  | PWA BOM | In Old BOM |
| 14 | U29 | 1 | 9FGL0651BKILFT | IC,IDT,9FGL0651BKILFT,G,VFQFN-40,SMD | INTEGRATED DEVICE TECHNOLOGY | 9FGL0651BKILFT |  | PWA BOM | In New BOM |
|  | U29 | 1 | 21050Q500-217-G | IC,IDT,871S1022EKLFT,G,VFQFN-32,SMD | INTEGRATED DEVICE TECHNOLOGY | 871S1022EKLFT |  | PWA BOM | In Old BOM |
| ##### Change Revision |  |  |  |  |  |  |  |  |  |
| Sheet | REV OF BOM | CUSTOMER | CUSTOMER P/N | PWA PN | PWA DESCRIPTION | PWA REV | DATE | Remark |  |
| PWA BOM |  | Customer |  |  |  |  |  | In New BOM |  |
| PWA BOM | X00 | Customer |  |  |  | X00 | 4/20/17 | In Old BOM |  |
| OOOOOOOOOOOOOOOOOOOOOOOOOOOOOOOOOOOOOOOOOOOOOOOOOOOOOOOOOOOOOOOOOOOOOOOOOOOOOOOOOOOOOOOOOO | OOOOOOOOOOOOOOOOOOOOOOOOOOOOOOOOOOOOOOOOOOOOOOOOOOOOOOOOOOOOOOOOOOOOOOOOOOOOOOOOOOOOOOOOOO | OOOOOOOOOOOOOOOOOOOOOOOOOOOOOOOOOOOOOOOOOOOOOOOOOOOOOOOOOOOOOOOOOOOOOOOOOOOOOOOOOOOOOOOOOO | OOOOOOOOOOOOOOOOOOOOOOOOOOOOOOOOOOOOOOOOOOOOOOOOOOOOOOOOOOOOOOOOOOOOOOOOOOOOOOOOOOOOOOOOOO | OOOOOOOOOOOOOOOOOOOOOOOOOOOOOOOOOOOOOOOOOOOOOOOOOOOOOOOOOOOOOOOOOOOOOOOOOOOOOOOOOOOOOOOOOO | OOOOOOOOOOOOOOOOOOOOOOOOOOOOOOOOOOOOOOOOOOOOOOOOOOOOOOOOOOOOOOOOOOOOOOOOOOOOOOOOOOOOOOOOOO | OOOOOOOOOOOOOOOOOOOOOOOOOOOOOOOOOOOOOOOOOOOOOOOOOOOOOOOOOOOOOOOOOOOOOOOOOOOOOOOOOOOOOOOOOO | OOOOOOOOOOOOOOOOOOOOOOOOOOOOOOOOOOOOOOOOOOOOOOOOOOOOOOOOOOOOOOOOOOOOOOOOOOOOOOOOOOOOOOOOOO | OOOOOOOOOOOOOOOOOOOOOOOOOOOOOOOOOOOOOOOOOOOOOOOOOOOOOOOOOOOOOOOOOOOOOOOOOOOOOOOOOOOOOOOOOO | OOOOOOOOOOOOOOOOOOOOOOOOOOOOOOOOOOOOOOOOOOOOOOOOOOOOOOOOOOOOOOOOOOOOOOOOOOOOOOOOOOOOOOOOOO |
| Second Source Change |  |  |  |  |  |  |  |  |  |
| Item | Location | Change Type | Foxconn P/N | Part Description | Manufacturer Full Name | Manufacturer P/N | RoHS | Sheet |  |
| 1 | L1 |  | 720101900-015-G | FB,60 Ohm@100MHz,+/-25%,3A,25mOhm,G,SMD0805 | MURATA ELEC. NORTH AMERICA | BLM21PG600SN1D | N | PWA BOM |  |
|  |  | ADD | 720101900-026-G | FB,60 Ohm@100MHz,+/-25%,3A,25mOhm,G,SMD0805 | SAMSUNG | CIC21P600NE | G | PWA BOM |  |
|  |  | Delete | 720102E00-129-G | FB,60 Ohm@100MHz,+/-25%,3A,40mOhm,G,SMD0805 | MAG.LAYERS, SCIENTIFIC-TECHNICS (KUNSHAN) CO., LTD. | GMLB-201209-0060P-N8 |  | PWA BOM |  |
|  |  | Delete | 720104100-074-G | FB,60 Ohm@100MHz,+/-25%,3A,30mOhm,G,SMD0805 | CHILISIN ELECTRONICS CORP. | PBY201209T-600Y-N |  | PWA BOM |  |
| 2 | PSRC2,PSTC6,PFTC6,PETC6,PSTC7,PFTC7,PETC7,PSTC8,PFTC8,PETC8,PSTC9,PFTC9,PETC9,PSRC17,PSTC3005,PFTC3005,PETC3005,PSTC3006,PFTC3006,PETC3006,PSTC3007,PFTC3007,PETC3007,PSTC3010,PFTC3010,PETC3010,PSTC3011,PFTC3011,PETC3011,PSTC3012,PFTC3012,PETC3012,PSTC3013,PFTC3013,PETC3013,PFTC3014,PETC3014,PFTC3015,PETC3015,PFTC3016,PETC3016 |  | 62012T500-015-G | CAP,22uF,+/-20%,X7S,25V,G,SMD1206 | MURATA ELEC. NORTH AMERICA | GRM31CC71E226ME11L |  | PWA BOM |  |
|  |  | Delete | 62012R900-026-G | CAP,22uF,+/-10%,X6S,25V,G,SMD1206 | SAMSUNG SEMICONDUCTOR | CL31X226KAHN3NE | G | PWA BOM |  |
| 3 | PSTL1,PFTL1,PETL1 |  | 630335M00-088-G | IND,820nH@100KHz,+/-20%,13A,8mOhm,SHLD,G,SMD | COOPER BUSSMANN, INC. | HCM0703-R82-R |  | PWA BOM |  |
|  |  | ADD | 63035Y800-051-G | Coil Ind,Shielded(SHLD),820nH@100KHz,+/-20%,13A,8mOhm,SMD,7.6*6.9*3.0,,,G | PULSE ELECTRONICS (SINGAPORE) | PA4341.821NLT | G | PWA BOM |  |
|  |  | ADD | SPS-06CZ-R82M-V1 | Ind,SPS-06CZ-R82M-V1 | MAG.LAYERS, SCIENTIFIC-TECHNICS (KUNSHAN) CO., LTD. | SPS-06CZ-R82M-V1 | G | PWA BOM |  |
|  |  | Delete | 63031F600-051-G | IND,820nH@100KHz,+/-20%,13A,8mOhm,SHLD,G,SMD | PULSE | PG0426.821NLT |  | PWA BOM |  |
| 4 | PSTL2,PFTL2,PETL2 |  | 630341400-088-G | IND,22nH@1MHz,+/-20%,19A,368uOhm,SHLD,G,SMD | COOPER BUSSMANN, INC. | FP0404R1-R022-R |  | PWA BOM |  |
|  |  | ADD | HCB0430-220 | IND,HCB0430-220 | Delta | HCB0430-220 | G | PWA BOM |  |
| 5 | PSRL2 |  | 63032PP00-088-G | IND,4.7uH@100KHz,+/-20%,5.5A,40mOhm,SHLD,G,SMD | COOPER BUSSMANN, INC. | HCM0703-4R7-R |  | PWA BOM |  |
|  |  | ADD | 63030PW00-034-G | Coil Ind,Shielded(SHLD),4.7uH@100KHz,+/-20%,5.5A,40mOhm,SMD,7.3*6.6*3.0,G | CYNTEC CO. LTD | PCMC063T-4R7MN | G | PWA BOM |  |
|  |  | ADD | SPS-06CZ-4R7M-V1 | IND,SPS-06CZ-4R7M-V1 | MAG.LAYERS, SCIENTIFIC-TECHNICS (KUNSHAN) CO., LTD. | SPS-06CZ-4R7M-V1 | G | PWA BOM |  |
|  |  | Delete | 63034RV00-15A-G | IND,4.7uH@100KHz,+/-20%,5.5A,40mOhm,SHLD,G,SMD | ITG | SMHC2511-4R7MHF |  | PWA BOM |  |
| 6 | PSRR19 |  | 61100YB00-017-G | RES,2.94KOhm,+/-0.1%,1/16W,G,SMD0402 | KOA SPEER ELECTRONICS, INC. | RN731ETTP2941B25 |  | PWA BOM |  |
|  |  | Delete | 61100YB00-011-G | RES,2.94KOhm,+/-0.1%,1/16W,G,SMD0402 | YAGEO | RT0402BRD072K94L |  | PWA BOM |  |
| 7 | U_AND1,U_AND2 |  | 310101400-031-G | IC,Gate&Inverter,74LVC1G08GW,1.65~5.5V,G,SOT353-5,SMD | NXP SEMICONDUCTORS | 74LVC1G08GW | N | PWA BOM |  |
|  |  | NO | 310103J00-223-G | IC,Gate&Inverter,NL17SZ08DFT2G,1.65~5.5V,G,SOT353-5,SMD | ON SEMICONDUCTOR CORP | NL17SZ08DFT2G | G | PWA BOM |  |
|  |  | ADD | 31010J400-131-G | IC,Gate&Inverter,TC7SZ08FU,1.8~5.5V,G,SSOP-5,SMD | TOSHIBA ELECTRONICS ASIA LTD | TC7SZ08FU | G | PWA BOM |  |
|  |  | Delete | 310102100-183-G | IC,Gate&Inverter,SN74LVC1G08DCKR,1.65~5.5V,G,SOT323-5,SMD | TEXAS INSTRUMENTS | SN74LVC1G08DCKR |  | PWA BOM |  |
| 8 | U_I2C_RE1 |  | 311004800-031-G | IC,Translator,PCA9617ADPJ,0.8~5.5V,2.2~5.5V,G,TSSOP-8,SMD | NXP SEMICONDUCTORS | PCA9617ADPJ |  | PWA BOM |  |
|  |  | NO | 311004V00-223-G | Logic IC,Translator,PCA9617ADMR2G,Vcca=0.8V~5.5V,Vccb=2.2V~5.5V,102ns,Micro8,8P,G | ON SEMICONDUCTOR CORP | PCA9617ADMR2G |  | PWA BOM |  |
|  |  | Delete | 311004K00-183-G | Logic IC,Translator,TCA9617ADGKR,Vcca=0.8V~5.5V;Vccb=2.2V~5.5V,250ns,VSSOP,8P,G | TEXAS INSTRUMENTS | TCA9617ADGKR |  | PWA BOM |  |
|  |  | Delete | 311004U00-252-G | Logic IC,Translator,PI6ULS5V9617AUEX,Vcca=0.8V~5.5V,Vccb=2.2V~5.5V,102ns,MSOP,8P,G | PERICOM SEMICONDUCTOR CORP | PI6ULS5V9617AUEX |  | PWA BOM |  |
| 9 | U_TMP1 |  | 32040J800-183-G | IC,Temp Sensor,TMP75AIDGKR,N/A,G,MSOP-8,SMD | TEXAS INSTRUMENTS | TMP75AIDGKR | N | PWA BOM |  |
|  |  | ADD | 32040PJ00-223-G | IC,Temperature Sensor,NCT75DMR2G,G,MSOP-8,SMD | ON SEMICONDUCTOR CORP | NCT75DMR2G |  | PWA BOM |  |
|  |  | Delete | 32040PJ00-223-G | IC,Temperature Sensor,NCT75DMR2G,G,MSOP-8,SMD | ON SEMICONDUCTOR CORP | NCT75DMR2G |  | PWA BOM |  |
| OOOOOOOOOOOOOOOOOOOOOOOOOOOOOOOOOOOOOOOOOOOOOOOOOOOOOOOOOOOOOOOOOOOOOOOOOOOOOOOOOOOOOOOOOO | OOOOOOOOOOOOOOOOOOOOOOOOOOOOOOOOOOOOOOOOOOOOOOOOOOOOOOOOOOOOOOOOOOOOOOOOOOOOOOOOOOOOOOOOOO | OOOOOOOOOOOOOOOOOOOOOOOOOOOOOOOOOOOOOOOOOOOOOOOOOOOOOOOOOOOOOOOOOOOOOOOOOOOOOOOOOOOOOOOOOO | OOOOOOOOOOOOOOOOOOOOOOOOOOOOOOOOOOOOOOOOOOOOOOOOOOOOOOOOOOOOOOOOOOOOOOOOOOOOOOOOOOOOOOOOOO | OOOOOOOOOOOOOOOOOOOOOOOOOOOOOOOOOOOOOOOOOOOOOOOOOOOOOOOOOOOOOOOOOOOOOOOOOOOOOOOOOOOOOOOOOO | OOOOOOOOOOOOOOOOOOOOOOOOOOOOOOOOOOOOOOOOOOOOOOOOOOOOOOOOOOOOOOOOOOOOOOOOOOOOOOOOOOOOOOOOOO | OOOOOOOOOOOOOOOOOOOOOOOOOOOOOOOOOOOOOOOOOOOOOOOOOOOOOOOOOOOOOOOOOOOOOOOOOOOOOOOOOOOOOOOOOO | OOOOOOOOOOOOOOOOOOOOOOOOOOOOOOOOOOOOOOOOOOOOOOOOOOOOOOOOOOOOOOOOOOOOOOOOOOOOOOOOOOOOOOOOOO | OOOOOOOOOOOOOOOOOOOOOOOOOOOOOOOOOOOOOOOOOOOOOOOOOOOOOOOOOOOOOOOOOOOOOOOOOOOOOOOOOOOOOOOOOO | OOOOOOOOOOOOOOOOOOOOOOOOOOOOOOOOOOOOOOOOOOOOOOOOOOOOOOOOOOOOOOOOOOOOOOOOOOOOOOOOOOOOOOOOOO |
| Master Materials Change |  |  |  |  |  |  |  |  |  |
| Item | Foxconn P/N | Orig._Usage | New_Usage | Part Description | Manufacturer Full Name | Manufacturer P/N | RoHS | Location | Sheet |
| 1 | 620101T02-015-G | 90 | 164 | CAP,100nF,+/-10%,X7R,16V,G,SMD0402 | MURATA ELEC. NORTH AMERICA | GRM155R71C104K | Y | (+)C15,C19,C216,C217,C224,C2101,C2102,C2103,C2104,C2105,C2106,C2107,C2108,C2109,C2110,C2111,C2112,C2113,C2114,C2115,C2116,C2117,C2118,C2119,C2120,C2121,C2122,C2123,C2124,C2125,C2126,C2127,C2128,C2129,C2130,C2131,C2132,C2133,C2134,C2135,C2136,C2137,C2138,C2139,C2140,C2141,C2142,C2143,C2144,C2145,C2146,C2147,C2148,C2149,C2169,C2171,C2176,C2177,C2178,C2179,C2180,C2181,C2182,C2183,C2184,C2185,C2186,C2187,C2188,C2189,C2190,C2191,C2192,C2193,C2194,C2195,C2196,C2197,C2232,C2233,C2234,C2235,C2237,C2239,C2240,C2241,C2242,C2254,C2255,C2256,C2259,C2260,C2261,C2262,C2263,C2264,C2265,C2266 (-)C225,C226,C227,C228,C229,C230,C231,C232,C233,C234,C235,C236,C237,C238,C239,C240,C241,C242,C243,C244,C245,C246,C247,C248 | PWA BOM |
|  | 620101T00-012-G |  |  | CAP,100nF,+/-10%,X7R,16V,G,SMD0402 | WALSIN | 0402B104K160CT |  |  | PWA BOM |
|  | 620101T00-026-G |  |  | CAP,100nF,+/-10%,X7R,16V,G,SMD0402 | SAMSUNG SEMICONDUCTOR | CL05B104KO5NNNC |  |  | PWA BOM |
|  | 620101T00-015-G |  |  | CAP,100nF,+/-10%,X7R,16V,G,SMD0402 | MURATA ELEC. NORTH AMERICA | GRM155R71C104KA88D |  |  | PWA BOM |
| 2 | 620100A00-015-G | 28 | 30 | CAP,10uF,+/-10%,X5R,16V,G,SMD1206 | MURATA ELEC. NORTH AMERICA | GRM31CR61C106K | N | (+)C2236,C2238 | PWA BOM |
|  | 620100A00-026-G |  |  | CAP,10uF,+/-10%,X5R,16V,G,SMD1206 | SAMSUNG SEMICONDUCTOR | CL31A106KOHNNNE |  |  | PWA BOM |
|  | 620100A03-023-G |  |  | CAP,10uF,+/-10%,X5R,16V,G,SMD1206 | TAIYO ELECTRIC IND.CO.LTD | EMK316BJ106KL-T |  |  | PWA BOM |
|  | 620100A00-012-G |  |  | CAP,10uF,+/-10%,X5R,16V,G,SMD1206 | WALSIN TECHNOLOGY CORPORATION | 1206X106K160CT |  |  | PWA BOM |
|  | 620100A00-011-G |  |  | CAP,10uF,+/-10%,X5R,16V,G,SMD1206 | YAGEO CORPORATION COMPONENT | CC1206KKX5R7BB106 |  |  | PWA BOM |
| 3 | 620105E00-015-G | 1 | 2 | CAP,1uF,+/-10%,X7R,10V,G,SMD0603 | MURATA ELEC. NORTH AMERICA | GRM188R71A105K |  | (+)C215 | PWA BOM |
|  | 620105E00-012-G |  |  | CAP,1uF,+/-10%,X7R,10V,G,SMD0603 | WALSIN TECHNOLOGY CORPORATION | 0603B105K100CT |  |  | PWA BOM |
|  | 620105E00-011-G |  |  | CAP,1uF,+/-10%,X7R,10V,G,SMD0603 | YAGEO CORPORATION COMPONENT | CC0603KRX7R6BB105 |  |  | PWA BOM |
|  | 620105E00-026-G |  |  | CAP,1uF,+/-10%,X7R,10V,G,SMD0603 | SAMSUNG SEMICONDUCTOR | CL10B105KP8NNNC |  |  | PWA BOM |
|  | 620105E01-023-G |  |  | CAP,1uF,+/-10%,X7R,10V,G,SMD0603 | TAIYO ELECTRIC IND.CO.LTD | LMK107B7105KA-T |  |  | PWA BOM |
| 4 | 620103600-015-G | 5 | 14 | CAP,10nF,+/-10%,X7R,25V,G,SMD0402 | MURATA ELEC. NORTH AMERICA | GRM155R71E103K | N | (+)C218,C219,C220,C221,C222,C2243,C2244,C2251,C2252 | PWA BOM |
|  | 620103600-012-G |  |  | CAP,10nF,+/-10%,X7R,25V,G,SMD0402 | WALSIN TECHNOLOGY CORPORATION | 0402B103K250CT |  |  | PWA BOM |
|  | 620103600-011-G |  |  | CAP,10nF,+/-10%,X7R,25V,G,SMD0402 | YAGEO CORPORATION COMPONENT | CC0402KRX7R8BB103 |  |  | PWA BOM |
|  | 620103600-026-G |  |  | CAP,10nF,+/-10%,X7R,25V,G,SMD0402 | SAMSUNG SEMICONDUCTOR | CL05B103KA5NNNC |  |  | PWA BOM |
|  | 620103601-023-G |  |  | CAP,10nF,+/-10%,X7R,25V,G,SMD0402 | TAIYO ELECTRIC IND.CO.LTD | TMK105B7103KV-F |  |  | PWA BOM |
| 5 | 62010L000-015-G | 1 | 2 | CAP,10uF,+/-20%,X5R,6.3V,G,SMD0603 | MURATA ELEC. NORTH AMERICA | GRM188R60J106M | N | (+)C214 | PWA BOM |
|  | 62010L000-023-G |  |  | CAP,10uF,+/-20%,X5R,6.3V,G,SMD0603 | TAIYO ELECTRIC IND.CO.LTD | JMK107BJ106MA-T |  |  | PWA BOM |
|  | 62010L000-012-G |  |  | CAP,10uF,+/-20%,X5R,6.3V,G,SMD0603 | WALSIN TECHNOLOGY CORPORATION | 0603X106M6R3CT |  |  | PWA BOM |
|  | 62010L000-026-G |  |  | CAP,10uF,+/-20%,X5R,6.3V,G,SMD0603 | SAMSUNG SEMICONDUCTOR | CL10A106MQ8NNNC |  |  | PWA BOM |
|  | 62010L000-011-G |  |  | CAP,10uF,+/-20%,X5R,6.3V,G,SMD0603 | YAGEO CORPORATION COMPONENT | CC0603MRX5R5BB106 |  |  | PWA BOM |
| 6 | 62011NF01-015-G | 1 | 2 | CAP,2.2uF,+/-10%,X7R,25V,G,SMD0805 | MURATA ELEC. NORTH AMERICA | GRM21BR71E225K |  | (+)C223 | PWA BOM |
|  | 62011NF00-026-G |  |  | CAP,2.2uF,+/-10%,X7R,25V,G,SMD0805 | SAMSUNG SEMICONDUCTOR | CL21B225KAFNNNE |  |  | PWA BOM |
|  | 62011NF00-023-G |  |  | CAP,2.2uF,+/-10%,X7R,25V,G,SMD0805 | TAIYO ELECTRIC IND.CO.LTD | TMK212B7225KG-TR |  |  | PWA BOM |
| 7 | 620114000-015-G | 0 | 3 | CAP,10uF,+/-10%,X5R,16V,G,SMD0805 | MURATA ELEC. NORTH AMERICA | GRM21BR61C106K | N | (+)C1946,C2081,C2253 | PWA BOM |
| 8 | 620105400-015-G | 0 | 10 | CAP,1uF,+/-10%,X7R,16V,G,SMD0603 | MURATA ELEC. NORTH AMERICA | GRM188R71C105K | N | (+)C1950,C2080,C2245,C2246,C2247,C2248,C2249,C2250,C2257,C2258 | PWA BOM |
|  | 620105400-012-G |  |  | CAP,1uF,+/-10%,X7R,16V,G,SMD0603 | WALSIN TECHNOLOGY CORPORATION | 0603B105K160CT |  |  | PWA BOM |
|  | 620105400-011-G |  |  | CAP,1uF,+/-10%,X7R,16V,G,SMD0603 | YAGEO CORPORATION COMPONENT | CC0603KRX7R7BB105 |  |  | PWA BOM |
|  | 620105400-026-G |  |  | CAP,1uF,+/-10%,X7R,16V,G,SMD0603 | SAMSUNG SEMICONDUCTOR | CL10B105KO8NNNC |  |  | PWA BOM |
|  | 620105400-023-G |  |  | CAP,1uF,+/-10%,X7R,16V,G,SMD0603 | TAIYO ELECTRIC IND.CO.LTD | EMK107B7105KA-T |  |  | PWA BOM |
| 9 | 62011LU00-015-G | 0 | 18 | CAP,100nF,+/-10%,X5R,16V,G,SMD0402 | MURATA ELEC. NORTH AMERICA | GRM155R61C104KA88D | Y | (+)C2198,C2208,C2209,C2210,C2211,C2212,C2213,C2214,C2215,C2216,C2217,C2218,C2219,C2220,C2221,C2222,C2223,C2224 | PWA BOM |
| 10 | 620109S00-015-G | 0 | 1 | CAP,4.7uF,+/-10%,X7R,10V,G,SMD0805 | MURATA ELEC. NORTH AMERICA | GRM21BR71A475K | N | (+)C2231 | PWA BOM |
|  | 620109S00-023-G |  |  | CAP,4.7uF,+/-10%,X7R,10V,G,SMD0805 | TAIYO ELECTRIC IND.CO.LTD | LMK212B7475KG-T |  |  | PWA BOM |
|  | 620109S00-026-G |  |  | CAP,4.7uF,+/-10%,X7R,10V,G,SMD0805 | SAMSUNG SEMICONDUCTOR | CL21B475KPFNNNE |  |  | PWA BOM |
| 11 | 620106200-015-G | 0 | 1 | CAP,10nF,+/-10%,X7R,16V,G,SMD0402 | MURATA ELEC. NORTH AMERICA | GRM155R71C103K | N | (+)C2267 | PWA BOM |
|  | 620106200-012-G |  |  | CAP,10nF,+/-10%,X7R,16V,G,SMD0402 | WALSIN | 0402B103K160CT |  |  | PWA BOM |
|  | 620106200-026-G |  |  | CAP,10nF,+/-10%,X7R,16V,G,SMD0402 | SAMSUNG | CL05B103KO5NNNC |  |  | PWA BOM |
|  | 620106200-023-G |  |  | CAP,10nF,+/-10%,X7R,16V,G,SMD0402 | TAIYO | EMK105B7103KV-F |  |  | PWA BOM |
| 12 | 62012UW00-015-G | 0 | 2 | CAP,6.8pF,+/-0.05pF,NPO(C0G),25V,G,SMD0402 | MURATA ELEC. NORTH AMERICA | GRM1555C1E6R8WA01D |  | (+)C2268,C2269 | PWA BOM |
| 13 | 72010JY00-015-G | 1 | 2 | FB,330 Ohm@100MHz,+/-25%,1.5A,70mOhm,G,SMD0603 | MURATA ELEC. NORTH AMERICA | BLM18SG331TN1D | N | (+)L4 | PWA BOM |
|  | 72010JB00-016-G |  |  | FB,330 Ohm@100MHz,+/-25%,1.5A,G,80mOhm,SMD0603 | TDK ELECTRONICS EUROPE GMBH | MPZ1608S331AT |  |  | PWA BOM |
| 14 | 72010FB01-016-G | 0 | 2 | FB,600 Ohm@100MHz,+/-25%,1A,150mOhm,G,SMD0603 | TDK ELECTRONICS EUROPE GMBH | MPZ1608S601AT | N | (+)L6,L28 | PWA BOM |
| 15 | 720102001-015-G | 0 | 1 | FB,30 Ohm@100MHz,+/-25%,3A,15mOhm,G,SMD0805 | MURATA ELEC. NORTH AMERICA | BLM21PG300SN1D | N | (+)L30 | PWA BOM |
| 16 | 720101L00-015-G | 0 | 1 | FB,600 Ohm@100MHz,+/-25%,200mA,500mOhm,G,SMD0603 | MURATA ELEC. NORTH AMERICA | BLM18AG601SN1D | N | (+)L31 | PWA BOM |
| 17 | 61010LA00-017-G | 3 | 84 | RES,4.7KOhm,+/-1%,1/16W,G,SMD0402 | KOA SPEER ELECTRONICS, INC. | RK73H1ETTP4701F | N | (+)R336,R1605,R1700,R1701,R1702,R1703,R1704,R1705,R1706,R1707,R1708,R1709,R1710,R1711,R1712,R1713,R1714,R1715,R1716,R1717,R1718,R1719,R1720,R1721,R1722,R1723,R1724,R1725,R1726,R1727,R1728,R1729,R1730,R1731,R1732,R1733,R1734,R1735,R1736,R1737,R1738,R1739,R1831,R1832,R1834,R1835,R1837,R1838,R1840,R1841,R1843,R1844,R1846,R1847,R1849,R1850,R1852,R1853,R1855,R1856,R1858,R1859,R1861,R1862,R1864,R1865,R1867,R1868,R1870,R1871,R1873,R1874,R1876,R1877,R1879,R1880,R1882,R1883,R1885,R1886,R2065 | PWA BOM |
|  | 61010LA00-012-G |  |  | RES,4.7KOhm,+/-1%,1/16W,G,SMD0402 | WALSIN | WR04X4701FTL |  |  | PWA BOM |
|  | 61010LA00-011-G |  |  | RES,4.7KOhm,+/-1%,1/16W,G,SMD0402 | YAGEO | RC0402FR-074K7L |  |  | PWA BOM |
|  | 61010LA00-044-G |  |  | RES,4.7KOhm,+/-1%,1/16W,G,SMD0402 | TA-I | RM04FTN4701 |  |  | PWA BOM |
| 18 | 610107A00-017-G | 57 | 120 | RES,0 Ohm,+/-5%,1/16W,G,SMD0402 | KOA SPEER ELECTRONICS, INC. | RK73Z1ETTP | N | (+)R60,R65,R568,R569,R570,R571,R1888,R1889,R1890,R1891,R1892,R1893,R1894,R1895,R1896,R1897,R1898,R1899,R1900,R1901,R1902,R1903,R1988,R1989,R1990,R1991,R1992,R1993,R1994,R1995,R1996,R1997,R1998,R1999,R2000,R2001,R2002,R2003,R2004,R2005,R2006,R2007,R2008,R2009,R2010,R2011,R2012,R2013,R2014,R2015,R2016,R2017,R2018,R2019,R2020,R2021,R2022,R2023,R2024,R2025,R2026,R2027,R2028,R2029,R2030,R2031,R2032,R2033,R2034,R2035,R2036,R2037,R2038,R2039,R2040,R2041,R2042,R2043,R2044,R2045,R2046,R2047,R2061,R2066,R2067,R2068,R2069,R2070 (-)PSRR8,R316,R325,R405,R421,R437,R453,R469,R485,R611,R627,R643,R659,R675,R691,R707,R723,R739,R755,R771,R787,R803,R819,R835,R851 | PWA BOM |
|  | 610107A00-012-G |  |  | RES,0 Ohm,+/-5%,1/16W,G,SMD0402 | WALSIN | WR04X000PTL |  |  | PWA BOM |
|  | 610107A00-011-G |  |  | RES,0 Ohm,+/-5%,1/16W,G,SMD0402 | YAGEO | RC0402JR-070RL |  |  | PWA BOM |
|  | 610107A00-044-G |  |  | RES,0 Ohm,+/-5%,1/16W,G,SMD0402 | TA-I | RM04JTN0 |  |  | PWA BOM |
|  | 610107A00-024-G |  |  | RES,0 Ohm,+/-5%,1/16W,G,SMD0402 | PANASONIC INDUSTRIAL CO.,LTD. | ERJ2GE0R00X |  |  | PWA BOM |
|  | 610107A00-029-G |  |  | RES,0 Ohm,+/-5%,1/16W,G,SMD0402 | VISHAY ENTER TECHNO LOGY.INC | CRCW04020000Z0ED |  |  | PWA BOM |
| 19 | 61011H500-017-G | 6 | 30 | RES,22 Ohm,+/-1%,1/16W,G,SMD0402 | KOA SPEER ELECTRONICS, INC. | RK73H1ETTP22R0F | N | (+)R338,R550,R552,R868,R869,R1833,R1836,R1839,R1842,R1845,R1848,R1851,R1854,R1857,R1860,R1863,R1866,R1869,R1872,R1875,R1878,R1881,R1884,R1887 | PWA BOM |
|  | 61011H500-012-G |  |  | RES,22 Ohm,+/-1%,1/16W,G,SMD0402 | WALSIN | WR04X22R0FTL |  |  | PWA BOM |
|  | 61011H500-011-G |  |  | RES,22 Ohm,+/-1%,1/16W,G,SMD0402 | YAGEO | RC0402FR-0722RL |  |  | PWA BOM |
|  | 61011H500-044-G |  |  | RES,22 Ohm,+/-1%,1/16W,G,SMD0402 | TA-I | RM04FTN22R0 |  |  | PWA BOM |
|  | 61011H500-024-G |  |  | RES,22 Ohm,+/-1%,1/16W,G,SMD0402 | PANASONIC INDUSTRIAL CO.,LTD. | ERJ2RKF22R0X |  |  | PWA BOM |
| 20 | 610107B00-017-G | 138 | 152 | RES,4.7KOhm,+/-5%,1/16W,G,SMD0402 | KOA SPEER ELECTRONICS, INC. | RK73B1ETTP472J | N | (+)R50,R51,R52,R53,R62,R96,R97,R546,R547,R548,R549,R553,R555,R556,R557,R559,R560,R866,R1078,R1079,R1569,R1570,R1571,R1572,R1573,R1574,R1575,R1576,R1577,R1578,R1579,R1580,R1581,R1582,R1583,R1584,R1585,R1586,R1587,R1588,R1589,R1590,R1591,R1592,R1593,R1594,R1595,R1596,R1597,R1598,R1599,R1600,R1601,R1602,R1603,R1668,R1681,R1684,R1688,R1694,R1697,R1783 (-)R322,R328,R408,R424,R440,R456,R472,R488,R587,R588,R589,R590,R591,R592,R593,R594,R595,R596,R597,R598,R599,R600,R601,R602,R603,R604,R605,R606,R607,R608,R609,R610,R614,R630,R646,R662,R678,R694,R710,R726,R742,R758,R774,R790,R806,R822,R838,R854 | PWA BOM |
|  | 610107B00-012-G |  |  | RES,4.7KOhm,+/-5%,1/16W,G,SMD0402 | WALSIN | WR04X472JTL |  |  | PWA BOM |
|  | 610107B00-011-G |  |  | RES,4.7KOhm,+/-5%,1/16W,G,SMD0402 | YAGEO | RC0402JR-074K7L |  |  | PWA BOM |
|  | 610107B00-044-G |  |  | RES,4.7KOhm,+/-5%,1/16W,G,SMD0402 | TA-I | RM04JTN472 |  |  | PWA BOM |
|  | 610107B00-024-G |  |  | RES,4.7KOhm,+/-5%,1/16W,G,SMD0402 | PANASONIC INDUSTRIAL CO.,LTD. | ERJ2GEJ472X |  |  | PWA BOM |
|  | 610107B00-029-G |  |  | RES,4.7KOhm,+/-5%,1/16W,G,SMD0402 | VISHAY ENTER TECHNO LOGY.INC | CRCW04024K70JNED |  |  | PWA BOM |
| 21 | 61010JY00-017-G | 2 | 10 | RES,220 Ohm,+/-5%,1/16W,G,SMD0402 | KOA SPEER ELECTRONICS, INC. | RK73B1ETTP221J | N | (+)R1672,R1673,R1679,R1683,R1687,R1698,R1780,R1782 | PWA BOM |
|  | 61010JY00-012-G |  |  | RES,220 Ohm,+/-5%,1/16W,G,SMD0402 | WALSIN | WR04X221JTL |  |  | PWA BOM |
|  | 61010JY00-011-G |  |  | RES,220 Ohm,+/-5%,1/16W,G,SMD0402 | YAGEO | RC0402JR-07220RL |  |  | PWA BOM |
|  | 61010JY00-044-G |  |  | RES,220 Ohm,+/-5%,1/16W,G,SMD0402 | TA-I | RM04JTN221 |  |  | PWA BOM |
| 22 | 610101V00-017-G | 0 | 40 | RES,22 Ohm,+/-5%,1/16W,G,SMD0402 | KOA SPEER ELECTRONICS, INC. | RK73B1ETTP220J | N | (+)R106,R1740,R1741,R1742,R1743,R1744,R1745,R1746,R1747,R1748,R1749,R1750,R1751,R1752,R1753,R1754,R1755,R1756,R1757,R1758,R1759,R1760,R1761,R1762,R1763,R1764,R1765,R1766,R1767,R1768,R1769,R1770,R1771,R1772,R1773,R1774,R1775,R1776,R1777,R1778 | PWA BOM |
|  | 610101V00-012-G |  |  | RES,22 Ohm,+/-5%,1/16W,G,SMD0402 | WALSIN | WR04X220JTL |  |  | PWA BOM |
|  | 610101V00-011-G |  |  | RES,22 Ohm,+/-5%,1/16W,G,SMD0402 | YAGEO | RC0402JR-0722RL |  |  | PWA BOM |
|  | 610101V00-044-G |  |  | RES,22 Ohm,+/-5%,1/16W,G,SMD0402 | TA-I | RM04JTN220 |  |  | PWA BOM |
|  | 610101V00-024-G |  |  | RES,22 Ohm,+/-5%,1/16W,G,SMD0402 | PANASONIC INDUSTRIAL CO.,LTD. | ERJ2GEJ220X |  |  | PWA BOM |
| 23 | 610115J00-017-G | 0 | 1 | RES,33 Ohm,+/-1%,1/16W,G,SMD0402 | KOA SPEER ELECTRONICS, INC. | RK73H1ETTP33R0F | N | (+)R315 | PWA BOM |
|  | 610115J00-012-G |  |  | RES,33 Ohm,+/-1%,1/16W,G,SMD0402 | WALSIN | WR04X33R0FTL |  |  | PWA BOM |
|  | 610115J00-011-G |  |  | RES,33 Ohm,+/-1%,1/16W,G,SMD0402 | YAGEO | RC0402FR-0733RL |  |  | PWA BOM |
|  | 610115J00-044-G |  |  | RES,33 Ohm,+/-1%,1/16W,G,SMD0402 | TA-I | RM04FTN33R0 |  |  | PWA BOM |
|  | 610115J00-024-G |  |  | RES,33 Ohm,+/-1%,1/16W,G,SMD0402 | PANASONIC INDUSTRIAL CO.,LTD. | ERJ2RKF33R0X |  |  | PWA BOM |
| 24 | 61100LQ00-017-G | 0 | 48 | RES,20KOhm,+/-1%,1/16W,G,SMD0402 | KOA SPEER ELECTRONICS, INC. | RN731ETTP2002F50 |  | (+)R348,R1522,R1523,R1524,R1525,R1526,R1527,R1528,R1529,R1530,R1531,R1532,R1533,R1534,R1535,R1536,R1537,R1538,R1539,R1540,R1541,R1542,R1543,R1544,R1545,R1546,R1547,R1548,R1549,R1550,R1551,R1552,R1553,R1554,R1555,R1556,R1557,R1558,R1559,R1560,R1561,R1562,R1563,R1564,R1565,R1566,R1567,R1568 | PWA BOM |
|  | 61100LQ00-012-G |  |  | RES,20KOhm,+/-1%,1/16W,G,SMD0402 | WALSIN | WF04T2002FTL |  |  | PWA BOM |
|  | 61100LQ00-011-G |  |  | RES,20KOhm,+/-1%,1/16W,G,SMD0402 | YAGEO | RT0402FRE0720KL |  |  | PWA BOM |
|  | 61100LQ00-044-G |  |  | RES,20KOhm,+/-1%,1/16W,G,SMD0402 | TA-I | RB04FTS2002 |  |  | PWA BOM |
| 25 | 610114J00-017-G | 3 | 5 | RES,2KOhm,+/-1%,1/16W,G,SMD0402 | KOA SPEER ELECTRONICS, INC. | RK73H1ETTP2001F | N | (+)R544,R545 | PWA BOM |
|  | 610114J00-012-G |  |  | RES,2KOhm,+/-1%,1/16W,G,SMD0402 | WALSIN | WR04X2001FTL |  |  | PWA BOM |
|  | 610114J00-011-G |  |  | RES,2KOhm,+/-1%,1/16W,G,SMD0402 | YAGEO | RC0402FR-072KL |  |  | PWA BOM |
|  | 610114J00-044-G |  |  | RES,2KOhm,+/-1%,1/16W,G,SMD0402 | TA-I | RM04FTN2001 |  |  | PWA BOM |
|  | 610114J00-024-G |  |  | RES,2KOhm,+/-1%,1/16W,G,SMD0402 | PANASONIC INDUSTRIAL CO.,LTD. | ERJ2RKF2001X |  |  | PWA BOM |
|  | 610114J00-029-G |  |  | RES,2KOhm,+/-1%,1/16W,G,SMD0402 | VISHAY ENTER TECHNO LOGY.INC | CRCW04022K00FKED |  |  | PWA BOM |
| 26 | 610100T00-017-G | 8 | 17 | RES,1KOhm,+/-5%,1/16W,G,SMD0402 | KOA SPEER ELECTRONICS, INC. | RK73B1ETTP102J | N | (+)R558,R561,R562,R564,R565,R566,R567,R2052,R2082 | PWA BOM |
|  | 610100T00-012-G |  |  | RES,1KOhm,+/-5%,1/16W,G,SMD0402 | WALSIN | WR04X102JTL |  |  | PWA BOM |
|  | 610100T00-011-G |  |  | RES,1KOhm,+/-5%,1/16W,G,SMD0402 | YAGEO | RC0402JR-071KL |  |  | PWA BOM |
|  | 610100T00-044-G |  |  | RES,1KOhm,+/-5%,1/16W,G,SMD0402 | TA-I | RM04JTN102 |  |  | PWA BOM |
|  | 610100T00-024-G |  |  | RES,1KOhm,+/-5%,1/16W,G,SMD0402 | PANASONIC INDUSTRIAL CO.,LTD. | ERJ2GEJ102X |  |  | PWA BOM |
| 27 | 61010L300-017-G | 2 | 10 | RES,1KOhm,+/-1%,1/16W,G,SMD0402 | KOA SPEER ELECTRONICS, INC. | RK73H1ETTP1001F | N | (+)R865,R1072,R1073,R1074,R1077,R1438,R1439,R1440 | PWA BOM |
|  | 61010L300-012-G |  |  | RES,1KOhm,+/-1%,1/16W,G,SMD0402 | WALSIN | WR04X1001FTL |  |  | PWA BOM |
|  | 61010L300-011-G |  |  | RES,1KOhm,+/-1%,1/16W,G,SMD0402 | YAGEO | RC0402FR-071KL |  |  | PWA BOM |
|  | 61010L300-044-G |  |  | RES,1KOhm,+/-1%,1/16W,G,SMD0402 | TA-I | RM04FTN1001 |  |  | PWA BOM |
|  | 61010L300-024-G |  |  | RES,1KOhm,+/-1%,1/16W,G,SMD0402 | PANASONIC INDUSTRIAL CO.,LTD. | ERJ2RKF1001X |  |  | PWA BOM |
|  | 61010L300-029-G |  |  | RES,1KOhm,+/-1%,1/16W,G,SMD0402 | VISHAY ENTER TECHNO LOGY.INC | CRCW04021K00FKED |  |  | PWA BOM |
| 28 | 61011BQ00-017-G | 1 | 2 | RES,2.2 Ohm,+/-5%,1/16W,G,SMD0402 | KOA SPEER ELECTRONICS, INC. | RK73B1ETTP2R2J | N | (+)R583 | PWA BOM |
|  | 61011BQ00-011-G |  |  | RES,2.2 Ohm,+/-5%,1/16W,G,SMD0402 | YAGEO CORPORATION COMPONENT | RC0402JR-072R2L |  |  | PWA BOM |
|  | 61011BQ00-012-G |  |  | RES,2.2 Ohm,+/-5%,1/16W,G,SMD0402 | WALSIN TECHNOLOGY CORPORATION | WR04X2R2JTL |  |  | PWA BOM |
|  | 61011BQ00-044-G |  |  | RES,2.2 Ohm,+/-5%,1/16W,G,SMD0402 | TA-I TECHNOLOGY CO., LTD | RM04JTN2R2 |  |  | PWA BOM |
| 29 | 610108300-017-G | 1 | 2 | RES,0 Ohm,+/-5%,1/10W,G,SMD0603 | KOA SPEER ELECTRONICS, INC. | RK73Z1JTTD | N | (+)R585 | PWA BOM |
|  | 610108300-012-G |  |  | RES,0 Ohm,+/-5%,1/10W,G,SMD0603 | WALSIN | WR06X000PTL |  |  | PWA BOM |
|  | 610108300-011-G |  |  | RES,0 Ohm,+/-5%,1/10W,G,SMD0603 | YAGEO | RC0603JR-070RL |  |  | PWA BOM |
|  | 610108300-044-G |  |  | RES,0 Ohm,+/-5%,1/10W,G,SMD0603 | TA-I | RM06JTN0 |  |  | PWA BOM |
|  | 610108300-024-G |  |  | RES,0 Ohm,+/-5%,1/10W,G,SMD0603 | PANASONIC INDUSTRIAL CO.,LTD. | ERJ3GEY0R00V |  |  | PWA BOM |
| 30 | 610118400-017-G | 0 | 32 | RES,27 Ohm,+/-1%,1/16W,G,SMD0402 | KOA SPEER ELECTRONICS, INC. | RK73H1ETTP27R0F | N | (+)R817,R818,R828,R830,R832,R833,R834,R860,R867,R1443,R1444,R1445,R1446,R1447,R1448,R1458,R1459,R1460,R1461,R1462,R1463,R1464,R1465,R1466,R1467,R1468,R1469,R1470,R1471,R1472,R1473,R1604 | PWA BOM |
|  | 610118400-012-G |  |  | RES,27 Ohm,+/-1%,1/16W,G,SMD0402 | WALSIN | WR04X27R0FTL |  |  | PWA BOM |
|  | 610118400-011-G |  |  | RES,27 Ohm,+/-1%,1/16W,G,SMD0402 | YAGEO | RC0402FR-0727RL |  |  | PWA BOM |
|  | 610118400-044-G |  |  | RES,27 Ohm,+/-1%,1/16W,G,SMD0402 | TA-I | RM04FTN27R0 |  |  | PWA BOM |
| 31 | 61100AH00-017-G | 1 | 36 | RES,10KOhm,+/-0.5%,1/16W,G,SMD0402 | KOA SPEER ELECTRONICS, INC. | RN731ETTP1002D25 | Y | (+)R1785,R1787,R1788,R1791,R1793,R1795,R1796,R1799,R1800,R1803,R1804,R1807,R1808,R1811,R1812,R1815,R1816,R1819,R1820,R1823,R1824,R1827,R1828,R2049,R2050,R2051,R2062,R2063,R2064,R2071,R2075,R2077,R2079,R2083,R2084 | PWA BOM |
|  | 61100AH00-012-G |  |  | RES,10KOhm,+/-0.5%,1/16W,G,SMD0402 | WALSIN | WF04U1002DTL |  |  | PWA BOM |
|  | 61100AH00-011-G |  |  | RES,10KOhm,+/-0.5%,1/16W,G,SMD0402 | YAGEO | RT0402DRE0710KL |  |  | PWA BOM |
|  | 61100AH00-044-G |  |  | RES,10KOhm,+/-0.5%,1/16W,G,SMD0402 | TA-I | RB04DTP1002 |  |  | PWA BOM |
| 32 | 61010FG00-017-G | 1 | 24 | RES,20KOhm,+/-5%,1/16W,G,SMD0402 | KOA SPEER ELECTRONICS, INC. | RK73B1ETTP203J | N | (+)R1786,R1789,R1790,R1792,R1794,R1797,R1798,R1801,R1802,R1805,R1806,R1809,R1810,R1813,R1814,R1817,R1818,R1821,R1822,R1825,R1826,R1829,R1830 | PWA BOM |
|  | 61010FG00-012-G |  |  | RES,20KOhm,+/-5%,1/16W,G,SMD0402 | WALSIN TECHNOLOGY CORPORATION | WR04X203JTL |  |  | PWA BOM |
|  | 61010FG00-011-G |  |  | RES,20KOhm,+/-5%,1/16W,G,SMD0402 | YAGEO CORPORATION COMPONENT | RC0402JR-0720KL |  |  | PWA BOM |
| 33 | 610107L00-017-G | 0 | 2 | RES,1 Ohm,+/-5%,1/10W,G,SMD0603 | KOA SPEER ELECTRONICS, INC. | RK73B1JTTD1R0J | N | (+)R1408,R1449 | PWA BOM |
| 34 | 610154800-017-G | 0 | 1 | RES,1 Ohm,+/-5%,1/8W,G,SMD0402 | KOA SPEER ELECTRONICS, INC. | SG73P1ETTP1R0J |  | (+)R2060 | PWA BOM |
| 35 | 41040B600-191-G | 0 | 1 | EEPROM,AT24C02C-SSHM-T,1.7~5.5V,2K,I2C,G,SOIC-8,SMD | ATMEL CORPORATION | AT24C02C-SSHM-T | N | (+)U_BP_FRU1 | PWA BOM |
| 36 | 21050LL00-217-G | 3 | 2 | IC,IDT,9ZXL0831AKLFT,G,VFQFPN-48,SMD | INTEGRATED DEVICE TECHNOLOGY | 9ZXL0831AKLFT |  | (+)U_Clock_B,U_Clock_A (-)U30,U31,U32 | PWA BOM |
| 37 | 31030CA00-031-G | 0 | 5 | IC,Switch,PCA9546APW,2.3~5.5V,G,TSSOP-16,SMD | NXP SEMICONDUCTORS | PCA9546APW | N | (+)U_MUX1,U_MUX2,U_MUX3,U_MUX4,U_MUX5 | PWA BOM |
|  | 31030YF00-252-G |  |  | Logic IC,Switch,PI4MSD5V9546ALEX,1.65V~5.5V,0.3ns,TSSOP,16P,G | PERICOM SEMICONDUCTOR CORP | PI4MSD5V9546ALEX |  |  | PWA BOM |
| 38 | 32040P400-399-G | 0 | 1 | IC,Voltage sensor,SLG4N020VTR,G,TDFN-8,SMD | SILEGO | SLG4N020VTR |  | (+)U_RESET | PWA BOM |
| 39 | 21081NC00-432-G | 1 | 2 | IC,LSI,500021009,A2,G,TFBGA-141,SMD | LSI LOGIC CORPORATION | 500021009 |  | (+)U_SF2 | PWA BOM |
| 40 | 310501200-183-G | 0 | 20 | IC,Buffer,SN74LVC1G07DCKR,1.65~5.5V,G,SC70-5,SMD | TEXAS INSTRUMENTS | SN74LVC1G07DCKR | N | (+)U209,U229,U230,U231,U232,U233,U234,U235,U236,U237,U238,U239,U240,U241,U242,U243,U244,U245,U246,U247 | PWA BOM |
| 41 | 220107K00-413-G | 0 | 1 | IC,PLD,10M02SCU169C8G,116MHz,3.3V,G,UBGA-169,SMD | ALTERA CORPORATION | 10M02SCU169C8G |  | (+)U248 | PWA BOM |
| 42 | 71012HD00-100-G | 0 | 1 | XTAL,25MHz,+/-20ppm,8pF,G,SMD | TXC CORPORATION | 7V25000054 |  | (+)X7 | PWA BOM |
| 43 | 71020SH00-107-G | 0 | 1 | OSC,25MHz,+/-25ppm,3.3V,15pF,G,SMD | DAISHINKU CORPORATION/DAISHINKU SINGAPORE PTE LTD/KDS | 1XSE025000AR122 |  | (+)Y3 | PWA BOM |
| 44 | 3406B0G00-309-G | 0 | 1 | CONN,Header,Pin Header,2X5,V/T,Bla,2.54mm,10u,G,SMD-10 | SAMTEC INC. | TSM-105-04-L-DV-A-P-TR |  | (+)J_CPLD_JTAG | PWA BOM |
| 45 | 9FGL0651BKILFT | 0 | 1 | IC,IDT,9FGL0651BKILFT,G,VFQFN-40,SMD | INTEGRATED DEVICE TECHNOLOGY | 9FGL0651BKILFT |  | (+)U29 | PWA BOM |
| 46 | 510301D00-223-G | 24 | 0 | MOS N,BSS138LT1G,50V,0.2A,3.5ohm@5V,G,SOT23-3,SMD | ON SEMICONDUCTOR CORP | BSS138LT1G | N | (-)Q1,Q2,Q3,Q4,Q5,Q6,Q7,Q8,Q9,Q10,Q11,Q12,Q13,Q14,Q15,Q16,Q17,Q18,Q19,Q20,Q21,Q22,Q23,Q24 | PWA BOM |
|  | 510309C00-237-G |  |  | MOS N,BSS138-7-F,50V,0.2A,3.5ohm@10V,G,SOT23-3,SMD | DIODES INCORPORATION | BSS138-7-F |  |  | PWA BOM |
|  | 510302R00-185-G |  |  | MOS N,BSS138,50V,0.22A,6ohm@4.5V,G,SOT23-3,SMD | FAIRCHILD SEMICONDUCTOR CORP | BSS138 |  |  | PWA BOM |
|  | 51030A800-221-G |  |  | MOS N,BSS138N,60V,0.23A,6ohm@4.5V,G,SOT23-3,SMD | INFINEON TECHNOLOGIES CORP. | BSS138N |  |  | PWA BOM |
| 47 | 61011H100-017-G | 14 | 0 | RES,220 Ohm,+/-1%,1/16W,G,SMD0402 | KOA SPEER ELECTRONICS, INC. | RK73H1ETTP2200F | N | (-)R870,R871,R872,R873,R922,R923,R924,R925,R926,R927,R928,R929,R930,R931 | PWA BOM |
|  | 61011H100-012-G |  |  | RES,220 Ohm,+/-1%,1/16W,G,SMD0402 | WALSIN | WR04X2200FTL |  |  | PWA BOM |
|  | 61011H100-011-G |  |  | RES,220 Ohm,+/-1%,1/16W,G,SMD0402 | YAGEO | RC0402FR-07220RL |  |  | PWA BOM |
|  | 61011H100-044-G |  |  | RES,220 Ohm,+/-1%,1/16W,G,SMD0402 | TA-I | RM04FTN2200 |  |  | PWA BOM |
|  | 61011H100-024-G |  |  | RES,220 Ohm,+/-1%,1/16W,G,SMD0402 | PANASONIC INDUSTRIAL CO.,LTD. | ERJ2RKF2200X |  |  | PWA BOM |
|  | 61011H100-029-G |  |  | RES,220 Ohm,+/-1%,1/16W,G,SMD0402 | VISHAY ENTER TECHNO LOGY.INC | CRCW0402220RFKEDC |  |  | PWA BOM |
| 48 | 41040HW00-191-G | 1 | 0 | EEPROM,AT24C02D-SSHM-T,1.7~3.6V,2K,I2C,G,SOIC-8,SMD | ATMEL CORPORATION | AT24C02D-SSHM-T |  | (-)U_BP_FRU1 | PWA BOM |
|  | 32040PJ00-223-G |  |  | IC,Temperature Sensor,NCT75DMR2G,G,MSOP-8,SMD | ON SEMICONDUCTOR CORP | NCT75DMR2G |  |  | PWA BOM |
| 49 | 310102400-183-G | 24 | 0 | IC,Gate&Inverter,SN74AHC1G32DBVR,2~5.5V,G,SOT23-5,SMD | TEXAS INSTRUMENTS | SN74AHC1G32DBVR | N | (-)U5,U6,U7,U8,U9,U10,U11,U12,U13,U14,U15,U16,U17,U18,U19,U20,U21,U22,U23,U24,U25,U26,U27,U28 | PWA BOM |
|  | 310106R00-185-G |  |  | IC,Gate&Inverter,NC7S32M5X,2~6V,G,SOT23-5,SMD | FAIRCHILD SEMICONDUCTOR CORP | NC7S32M5X |  |  | PWA BOM |
|  | 310106U00-031-G |  |  | IC,Gate&Inverter,74AHC1G32GV,2~5.5V,G,SC74A-5,SMD | NXP SEMICONDUCTORS | 74AHC1G32GV |  |  | PWA BOM |
| 50 | 21050Q500-217-G | 1 | 0 | IC,IDT,871S1022EKLFT,G,VFQFN-32,SMD | INTEGRATED DEVICE TECHNOLOGY | 871S1022EKLFT |  | (-)U29 | PWA BOM |
| 51 | 2A5910Q00-HYM-G | 8 | 0 | SMT NUT,CARBON STEEL,G,FIVETECH,82-059-01-022-01-RL | Fivetech Technology Inc. | 82-059-01-022-01-RL |  | (-)H1,H2,H3,H4,H7,H8,H9,H10 | PWA BOM |
|  | 2A5914300-G44-G |  |  | 螺母,Nut,CARBON STEEL,N/A,4.7,3.5,7,TIN Plating,圓柱,G,00 | PennEngineering Fastening | YSMTSO-47670-ET |  |  | PWA BOM |
| OOOOOOOOOOOOOOOOOOOOOOOOOOOOOOOOOOOOOOOOOOOOOOOOOOOOOOOOOOOOOOOOOOOOOOOOOOOOOOOOOOOOOOOOOO | OOOOOOOOOOOOOOOOOOOOOOOOOOOOOOOOOOOOOOOOOOOOOOOOOOOOOOOOOOOOOOOOOOOOOOOOOOOOOOOOOOOOOOOOOO | OOOOOOOOOOOOOOOOOOOOOOOOOOOOOOOOOOOOOOOOOOOOOOOOOOOOOOOOOOOOOOOOOOOOOOOOOOOOOOOOOOOOOOOOOO | OOOOOOOOOOOOOOOOOOOOOOOOOOOOOOOOOOOOOOOOOOOOOOOOOOOOOOOOOOOOOOOOOOOOOOOOOOOOOOOOOOOOOOOOOO | OOOOOOOOOOOOOOOOOOOOOOOOOOOOOOOOOOOOOOOOOOOOOOOOOOOOOOOOOOOOOOOOOOOOOOOOOOOOOOOOOOOOOOOOOO | OOOOOOOOOOOOOOOOOOOOOOOOOOOOOOOOOOOOOOOOOOOOOOOOOOOOOOOOOOOOOOOOOOOOOOOOOOOOOOOOOOOOOOOOOO | OOOOOOOOOOOOOOOOOOOOOOOOOOOOOOOOOOOOOOOOOOOOOOOOOOOOOOOOOOOOOOOOOOOOOOOOOOOOOOOOOOOOOOOOOO | OOOOOOOOOOOOOOOOOOOOOOOOOOOOOOOOOOOOOOOOOOOOOOOOOOOOOOOOOOOOOOOOOOOOOOOOOOOOOOOOOOOOOOOOOO | OOOOOOOOOOOOOOOOOOOOOOOOOOOOOOOOOOOOOOOOOOOOOOOOOOOOOOOOOOOOOOOOOOOOOOOOOOOOOOOOOOOOOOOOOO |  |
| TLA Parts Change |  |  |  |  |  |  |  |  |  |
| Item | Foxconn P/N | Qty | Part Description | Manufacturer Full Name | Manufacturer P/N | RoHS | Location | Remark |  |
| BOM Change List Date:Sat May 27 11:48:23 GMT+08:00 2017 |  |  |  |  |  |  |  |  |  |
| New BOM file : C:\<user>\Barreleye_G2-Tri-mode BPX24-EVT-X00-BOM-X02_20170517_for 2nd source.xls |  |  |  |  |  |  |  |  |  |
| Old BOM file : C:\<user>\Barreleye_G2-Tri-mode BPX24-EVT-X00-BOM-X01_20170509.xls |  |  |  |  |  |  |  |  |  |
| ##### Add Parts |  |  |  |  |  |  |  |  |  |
| Item | Location | Qty | Foxconn P/N | Part Description | Manufacturer Full Name | Manufacturer P/N | RoHS | Sheet |  |
| 1 | C2270 | 1 | 620101T02-015-G | CAP,100nF,+/-10%,X7R,16V,G,SMD0402 | MURATA ELEC. NORTH AMERICA | GRM155R71C104K | Y | PWA BOM |  |
|  |  |  | 620101T00-012-G | CAP,100nF,+/-10%,X7R,16V,G,SMD0402 | WALSIN | 0402B104K160CT |  | PWA BOM |  |
|  |  |  | 620101T00-026-G | CAP,100nF,+/-10%,X7R,16V,G,SMD0402 | SAMSUNG SEMICONDUCTOR | CL05B104KO5NNNC |  | PWA BOM |  |
|  |  |  | 620101T00-015-G | CAP,100nF,+/-10%,X7R,16V,G,SMD0402 | MURATA ELEC. NORTH AMERICA | GRM155R71C104KA88D |  | PWA BOM |  |
| 2 | OSC2 | 1 | 71020NS00-967-G | OSC,25MHz,+/-25ppm,3.3V,15pF,G,SMD | SaRonix-eCERA Corporation | FK2500025 |  | PWA BOM |  |
|  |  |  | 710209J00-100-G | OSC,25MHz,+/-25ppm,3.3V,15pF,G,SMD | TXC CORPORATION | 7X25000008 |  | PWA BOM |  |
| 3 | PSRR8,R2085,R2086 | 3 | 610107A00-017-G | RES,0 Ohm,+/-5%,1/16W,G,SMD0402 | KOA SPEER ELECTRONICS, INC. | RK73Z1ETTP | N | PWA BOM |  |
|  |  |  | 610107A00-012-G | RES,0 Ohm,+/-5%,1/16W,G,SMD0402 | WALSIN | WR04X000PTL |  | PWA BOM |  |
|  |  |  | 610107A00-011-G | RES,0 Ohm,+/-5%,1/16W,G,SMD0402 | YAGEO | RC0402JR-070RL |  | PWA BOM |  |
|  |  |  | 610107A00-044-G | RES,0 Ohm,+/-5%,1/16W,G,SMD0402 | TA-I | RM04JTN0 |  | PWA BOM |  |
|  |  |  | 610107A00-024-G | RES,0 Ohm,+/-5%,1/16W,G,SMD0402 | PANASONIC INDUSTRIAL CO.,LTD. | ERJ2GE0R00X |  | PWA BOM |  |
|  |  |  | 610107A00-029-G | RES,0 Ohm,+/-5%,1/16W,G,SMD0402 | VISHAY ENTER TECHNO LOGY.INC | CRCW04020000Z0ED |  | PWA BOM |  |
| 4 | R2148 | 1 | 61011H500-017-G | RES,22 Ohm,+/-1%,1/16W,G,SMD0402 | KOA SPEER ELECTRONICS, INC. | RK73H1ETTP22R0F | N | PWA BOM |  |
|  |  |  | 61011H500-012-G | RES,22 Ohm,+/-1%,1/16W,G,SMD0402 | WALSIN | WR04X22R0FTL |  | PWA BOM |  |
|  |  |  | 61011H500-011-G | RES,22 Ohm,+/-1%,1/16W,G,SMD0402 | YAGEO | RC0402FR-0722RL |  | PWA BOM |  |
|  |  |  | 61011H500-044-G | RES,22 Ohm,+/-1%,1/16W,G,SMD0402 | TA-I | RM04FTN22R0 |  | PWA BOM |  |
|  |  |  | 61011H500-024-G | RES,22 Ohm,+/-1%,1/16W,G,SMD0402 | PANASONIC INDUSTRIAL CO.,LTD. | ERJ2RKF22R0X |  | PWA BOM |  |
| 5 | R2128,R2129,R2130,R2131,R2132,R2133,R2134,R2135,R2136,R2137,R2138,R2139,R2140,R2141,R2142,R2143,R2144,R2145,R2146,R2147,R2149 | 21 | 610107B00-017-G | RES,4.7KOhm,+/-5%,1/16W,G,SMD0402 | KOA SPEER ELECTRONICS, INC. | RK73B1ETTP472J | N | PWA BOM |  |
|  |  |  | 610107B00-012-G | RES,4.7KOhm,+/-5%,1/16W,G,SMD0402 | WALSIN | WR04X472JTL |  | PWA BOM |  |
|  |  |  | 610107B00-011-G | RES,4.7KOhm,+/-5%,1/16W,G,SMD0402 | YAGEO | RC0402JR-074K7L |  | PWA BOM |  |
|  |  |  | 610107B00-044-G | RES,4.7KOhm,+/-5%,1/16W,G,SMD0402 | TA-I | RM04JTN472 |  | PWA BOM |  |
|  |  |  | 610107B00-024-G | RES,4.7KOhm,+/-5%,1/16W,G,SMD0402 | PANASONIC INDUSTRIAL CO.,LTD. | ERJ2GEJ472X |  | PWA BOM |  |
|  |  |  | 610107B00-029-G | RES,4.7KOhm,+/-5%,1/16W,G,SMD0402 | VISHAY ENTER TECHNO LOGY.INC | CRCW04024K70JNED |  | PWA BOM |  |
| 6 | H1,H2,H3,H4,H7,H8,H9,H10,H30,H31 | 10 | 2A5910Q00-HYM-G | SMT NUT,CARBON STEEL,G,FIVETECH,82-059-01-022-01-RL | Fivetech Technology Inc. | 82-059-01-022-01-RL |  | PWA BOM |  |
| ##### Remove Parts |  |  |  |  |  |  |  |  |  |
| Item | Location | Qty | Foxconn P/N | Part Description | Manufacturer Full Name | Manufacturer P/N | RoHS | Sheet |  |
| 1 | C2142,C2144,C2146,C2148,C2179,C2180,C2181,C2182,C2183,C2184,C2185,C2186,C2187,C2188,C2189,C2190,C2191,C2192,C2193,C2194,C2195,C2196,C2197 | 23 | 620101T02-015-G | CAP,100nF,+/-10%,X7R,16V,G,SMD0402 | MURATA ELEC. NORTH AMERICA | GRM155R71C104K | Y | PWA BOM |  |
|  |  |  | 620101T00-012-G | CAP,100nF,+/-10%,X7R,16V,G,SMD0402 | WALSIN | 0402B104K160CT |  | PWA BOM |  |
|  |  |  | 620101T00-026-G | CAP,100nF,+/-10%,X7R,16V,G,SMD0402 | SAMSUNG SEMICONDUCTOR | CL05B104KO5NNNC |  | PWA BOM |  |
|  |  |  | 620101T00-015-G | CAP,100nF,+/-10%,X7R,16V,G,SMD0402 | MURATA ELEC. NORTH AMERICA | GRM155R71C104KA88D |  | PWA BOM |  |
| 2 | C2267 | 1 | 620106200-015-G | CAP,10nF,+/-10%,X7R,16V,G,SMD0402 | MURATA ELEC. NORTH AMERICA | GRM155R71C103K | N | PWA BOM |  |
|  |  |  | 620106200-012-G | CAP,10nF,+/-10%,X7R,16V,G,SMD0402 | WALSIN | 0402B103K160CT | G | PWA BOM |  |
|  |  |  | 620106200-026-G | CAP,10nF,+/-10%,X7R,16V,G,SMD0402 | SAMSUNG | CL05B103KO5NNNC | G | PWA BOM |  |
|  |  |  | 620106200-023-G | CAP,10nF,+/-10%,X7R,16V,G,SMD0402 | TAIYO | EMK105B7103KV-F | G | PWA BOM |  |
| 3 | R1831,R1832,R1834,R1835,R1837,R1838,R1840,R1841,R1843,R1844,R1846,R1847,R1849,R1850,R1852,R1853,R1855,R1856,R1858,R1859,R1861,R1862,R1864,R1865,R1867,R1868,R1870,R1871,R1873,R1874,R1876,R1877,R1879,R1880,R1882,R1883,R1885,R1886,R2065 | 39 | 61010LA00-017-G | RES,4.7KOhm,+/-1%,1/16W,G,SMD0402 | KOA SPEER ELECTRONICS, INC. | RK73H1ETTP4701F | N | PWA BOM |  |
|  |  |  | 61010LA00-012-G | RES,4.7KOhm,+/-1%,1/16W,G,SMD0402 | WALSIN | WR04X4701FTL |  | PWA BOM |  |
|  |  |  | 61010LA00-011-G | RES,4.7KOhm,+/-1%,1/16W,G,SMD0402 | YAGEO | RC0402FR-074K7L |  | PWA BOM |  |
|  |  |  | 61010LA00-044-G | RES,4.7KOhm,+/-1%,1/16W,G,SMD0402 | TA-I | RM04FTN4701 |  | PWA BOM |  |
| 4 | R2068,R2069 | 2 | 610107A00-017-G | RES,0 Ohm,+/-5%,1/16W,G,SMD0402 | KOA SPEER ELECTRONICS, INC. | RK73Z1ETTP | N | PWA BOM |  |
|  |  |  | 610107A00-012-G | RES,0 Ohm,+/-5%,1/16W,G,SMD0402 | WALSIN | WR04X000PTL |  | PWA BOM |  |
|  |  |  | 610107A00-011-G | RES,0 Ohm,+/-5%,1/16W,G,SMD0402 | YAGEO | RC0402JR-070RL |  | PWA BOM |  |
|  |  |  | 610107A00-044-G | RES,0 Ohm,+/-5%,1/16W,G,SMD0402 | TA-I | RM04JTN0 |  | PWA BOM |  |
|  |  |  | 610107A00-024-G | RES,0 Ohm,+/-5%,1/16W,G,SMD0402 | PANASONIC INDUSTRIAL CO.,LTD. | ERJ2GE0R00X |  | PWA BOM |  |
|  |  |  | 610107A00-029-G | RES,0 Ohm,+/-5%,1/16W,G,SMD0402 | VISHAY ENTER TECHNO LOGY.INC | CRCW04020000Z0ED |  | PWA BOM |  |
| 5 | R1833,R1836,R1839,R1842,R1845,R1848,R1851,R1854,R1857,R1860,R1863,R1866,R1869,R1872,R1875,R1878,R1881,R1884,R1887 | 19 | 61011H500-017-G | RES,22 Ohm,+/-1%,1/16W,G,SMD0402 | KOA SPEER ELECTRONICS, INC. | RK73H1ETTP22R0F | N | PWA BOM |  |
|  |  |  | 61011H500-012-G | RES,22 Ohm,+/-1%,1/16W,G,SMD0402 | WALSIN | WR04X22R0FTL |  | PWA BOM |  |
|  |  |  | 61011H500-011-G | RES,22 Ohm,+/-1%,1/16W,G,SMD0402 | YAGEO | RC0402FR-0722RL |  | PWA BOM |  |
|  |  |  | 61011H500-044-G | RES,22 Ohm,+/-1%,1/16W,G,SMD0402 | TA-I | RM04FTN22R0 |  | PWA BOM |  |
|  |  |  | 61011H500-024-G | RES,22 Ohm,+/-1%,1/16W,G,SMD0402 | PANASONIC INDUSTRIAL CO.,LTD. | ERJ2RKF22R0X |  | PWA BOM |  |
| 6 | R315 | 1 | 610115J00-017-G | RES,33 Ohm,+/-1%,1/16W,G,SMD0402 | KOA SPEER ELECTRONICS, INC. | RK73H1ETTP33R0F | N | PWA BOM |  |
|  |  |  | 610115J00-012-G | RES,33 Ohm,+/-1%,1/16W,G,SMD0402 | WALSIN | WR04X33R0FTL |  | PWA BOM |  |
|  |  |  | 610115J00-011-G | RES,33 Ohm,+/-1%,1/16W,G,SMD0402 | YAGEO | RC0402FR-0733RL |  | PWA BOM |  |
|  |  |  | 610115J00-044-G | RES,33 Ohm,+/-1%,1/16W,G,SMD0402 | TA-I | RM04FTN33R0 |  | PWA BOM |  |
|  |  |  | 610115J00-024-G | RES,33 Ohm,+/-1%,1/16W,G,SMD0402 | PANASONIC INDUSTRIAL CO.,LTD. | ERJ2RKF33R0X |  | PWA BOM |  |
| 7 | R1562,R1564,R1566,R1568 | 4 | 61100LQ00-017-G | RES,20KOhm,+/-1%,1/16W,G,SMD0402 | KOA SPEER ELECTRONICS, INC. | RN731ETTP2002F50 |  | PWA BOM |  |
|  |  |  | 61100LQ00-012-G | RES,20KOhm,+/-1%,1/16W,G,SMD0402 | WALSIN | WF04T2002FTL |  | PWA BOM |  |
|  |  |  | 61100LQ00-011-G | RES,20KOhm,+/-1%,1/16W,G,SMD0402 | YAGEO | RT0402FRE0720KL |  | PWA BOM |  |
|  |  |  | 61100LQ00-044-G | RES,20KOhm,+/-1%,1/16W,G,SMD0402 | TA-I | RB04FTS2002 |  | PWA BOM |  |
| 8 | U229,U230,U231,U232,U233,U234,U235,U236,U237,U238,U239,U240,U241,U242,U243,U244,U245,U246,U247 | 19 | 310501200-183-G | IC,Buffer,SN74LVC1G07DCKR,1.65~5.5V,G,SC70-5,SMD | TEXAS INSTRUMENTS | SN74LVC1G07DCKR | N | PWA BOM |  |
| 9 | Y3 | 1 | 71020SH00-107-G | OSC,25MHz,+/-25ppm,3.3V,15pF,G,SMD | DAISHINKU CORPORATION/DAISHINKU SINGAPORE PTE LTD/KDS | 1XSE025000AR122 |  | PWA BOM |  |
| ##### Change Parts |  |  |  |  |  |  |  |  |  |
| Item | Location | Qty | Foxconn P/N | Part Description | Manufacturer Full Name | Manufacturer P/N | RoHS | Sheet | Remark |
| 1 | PSTL1,PFTL1,PETL1 | 3 | 630335M00-088-G | IND,820nH@100KHz,+/-20%,13A,8mOhm,SHLD,G,SMD | COOPER BUSSMANN, INC. | HCM0703-R82-R |  | PWA BOM | In New BOM |
|  |  |  | 63035Y800-051-G | Coil Ind,Shielded(SHLD),820nH@100KHz,+/-20%,13A,8mOhm,SMD,7.6*6.9*3.0,,,G | PULSE ELECTRONICS (SINGAPORE) | PA4341.821NLT | G | PWA BOM | In New BOM |
|  |  |  | 63032RP05-129-G | IND,820nH@100KHz,+/-20%,13A,8mOhm,SHLD,G,SMD | MAG.LAYERS, SCIENTIFIC-TECHNICS (KUNSHAN) CO., LTD. | SPS-06CZ-R82M-V1 | G | PWA BOM | In New BOM |
|  | PSTL1,PFTL1,PETL1 | 3 | 630335M00-088-G | IND,820nH@100KHz,+/-20%,13A,8mOhm,SHLD,G,SMD | COOPER BUSSMANN, INC. | HCM0703-R82-R |  | PWA BOM | In Old BOM |
|  |  |  | 63035Y800-051-G | Coil Ind,Shielded(SHLD),820nH@100KHz,+/-20%,13A,8mOhm,SMD,7.6*6.9*3.0,,,G | PULSE ELECTRONICS (SINGAPORE) | PA4341.821NLT | G | PWA BOM | In Old BOM |
|  |  |  | SPS-06CZ-R82M-V1 | Ind,SPS-06CZ-R82M-V1 | MAG.LAYERS, SCIENTIFIC-TECHNICS (KUNSHAN) CO., LTD. | SPS-06CZ-R82M-V1 | G | PWA BOM | In Old BOM |
| 2 | J_CPLD_JTAG | 1 | 15-91-2065 | CONN,Header,Pin Header,1X6,Bla,2.54mm,10u,G,SMD-6 | MOLEX INCORPORATED | 15-91-2065 |  | PWA BOM | In New BOM |
|  | J_CPLD_JTAG | 1 | 3406B0G00-309-G | CONN,Header,Pin Header,2X5,V/T,Bla,2.54mm,10u,G,SMD-10 | SAMTEC INC. | TSM-105-04-L-DV-A-P-TR |  | PWA BOM | In Old BOM |
| 3 | R875,R877,R879,R881,R883,R885,R887,R889,R891,R893,R895,R897,R899,R901,R903,R905,R907,R909,R911,R913,R915,R917,R919,R921 | 24 | 61015K700-017-G | RES,3.3 Ohm,+/-5%,1/2W,G,SMD1210 | KOA SPEER ELECTRONICS, INC. | RK73B2ETTD3R3J |  | PWA BOM | In New BOM |
|  | R875,R877,R879,R881,R883,R885,R887,R889,R891,R893,R895,R897,R899,R901,R903,R905,R907,R909,R911,R913,R915,R917,R919,R921 | 24 | 610113A00-017-G | RES,2.2 Ohm,+/-5%,1/2W,G,SMD1210 | KOA SPEER ELECTRONICS, INC. | RK73B2ETTD2R2J | N | PWA BOM | In Old BOM |
|  |  |  | 610113A00-012-G | RES,2.2 Ohm,+/-5%,1/2W,G,SMD1210 | WALSIN TECHNOLOGY CORPORATION | WF10P2R2JTL |  | PWA BOM | In Old BOM |
|  |  |  | 610113A00-011-G | RES,2.2 Ohm,+/-5%,1/2W,G,SMD1210 | YAGEO CORPORATION COMPONENT | RC1210JR-072R2L |  | PWA BOM | In Old BOM |
| 4 | U29 | 1 | 21050RJ00-217-G | IC,IDT,9FGL0651BKILFT,G,VFQFPN-40,SMD | INTEGRATED DEVICE TECHNOLOGY | 9FGL0651BKILFT |  | PWA BOM | In New BOM |
|  | U29 | 1 | 9FGL0651BKILFT | IC,IDT,9FGL0651BKILFT,G,VFQFN-40,SMD | INTEGRATED DEVICE TECHNOLOGY | 9FGL0651BKILFT |  | PWA BOM | In Old BOM |
| ##### Change Revision |  |  |  |  |  |  |  |  |  |
| Sheet | REV OF BOM | CUSTOMER | CUSTOMER P/N | PWA PN | PWA DESCRIPTION | PWA REV | DATE | Remark |  |
| OOOOOOOOOOOOOOOOOOOOOOOOOOOOOOOOOOOOOOOOOOOOOOOOOOOOOOOOOOOOOOOOOOOOOOOOOOOOOOOOOOOOOOOOOO | OOOOOOOOOOOOOOOOOOOOOOOOOOOOOOOOOOOOOOOOOOOOOOOOOOOOOOOOOOOOOOOOOOOOOOOOOOOOOOOOOOOOOOOOOO | OOOOOOOOOOOOOOOOOOOOOOOOOOOOOOOOOOOOOOOOOOOOOOOOOOOOOOOOOOOOOOOOOOOOOOOOOOOOOOOOOOOOOOOOOO | OOOOOOOOOOOOOOOOOOOOOOOOOOOOOOOOOOOOOOOOOOOOOOOOOOOOOOOOOOOOOOOOOOOOOOOOOOOOOOOOOOOOOOOOOO | OOOOOOOOOOOOOOOOOOOOOOOOOOOOOOOOOOOOOOOOOOOOOOOOOOOOOOOOOOOOOOOOOOOOOOOOOOOOOOOOOOOOOOOOOO | OOOOOOOOOOOOOOOOOOOOOOOOOOOOOOOOOOOOOOOOOOOOOOOOOOOOOOOOOOOOOOOOOOOOOOOOOOOOOOOOOOOOOOOOOO | OOOOOOOOOOOOOOOOOOOOOOOOOOOOOOOOOOOOOOOOOOOOOOOOOOOOOOOOOOOOOOOOOOOOOOOOOOOOOOOOOOOOOOOOOO | OOOOOOOOOOOOOOOOOOOOOOOOOOOOOOOOOOOOOOOOOOOOOOOOOOOOOOOOOOOOOOOOOOOOOOOOOOOOOOOOOOOOOOOOOO | OOOOOOOOOOOOOOOOOOOOOOOOOOOOOOOOOOOOOOOOOOOOOOOOOOOOOOOOOOOOOOOOOOOOOOOOOOOOOOOOOOOOOOOOOO | OOOOOOOOOOOOOOOOOOOOOOOOOOOOOOOOOOOOOOOOOOOOOOOOOOOOOOOOOOOOOOOOOOOOOOOOOOOOOOOOOOOOOOOOOO |
| Second Source Change |  |  |  |  |  |  |  |  |  |
| Item | Location | Change Type | Foxconn P/N | Part Description | Manufacturer Full Name | Manufacturer P/N | RoHS | Sheet |  |
| 1 | PSTL1,PFTL1,PETL1 |  | 630335M00-088-G | IND,820nH@100KHz,+/-20%,13A,8mOhm,SHLD,G,SMD | COOPER BUSSMANN, INC. | HCM0703-R82-R |  | PWA BOM |  |
|  |  | NO | 63035Y800-051-G | Coil Ind,Shielded(SHLD),820nH@100KHz,+/-20%,13A,8mOhm,SMD,7.6*6.9*3.0,,,G | PULSE ELECTRONICS (SINGAPORE) | PA4341.821NLT | G | PWA BOM |  |
|  |  | ADD | 63032RP05-129-G | IND,820nH@100KHz,+/-20%,13A,8mOhm,SHLD,G,SMD | MAG.LAYERS, SCIENTIFIC-TECHNICS (KUNSHAN) CO., LTD. | SPS-06CZ-R82M-V1 | G | PWA BOM |  |
|  |  | Delete | SPS-06CZ-R82M-V1 | Ind,SPS-06CZ-R82M-V1 | MAG.LAYERS, SCIENTIFIC-TECHNICS (KUNSHAN) CO., LTD. | SPS-06CZ-R82M-V1 | G | PWA BOM |  |
| OOOOOOOOOOOOOOOOOOOOOOOOOOOOOOOOOOOOOOOOOOOOOOOOOOOOOOOOOOOOOOOOOOOOOOOOOOOOOOOOOOOOOOOOOO | OOOOOOOOOOOOOOOOOOOOOOOOOOOOOOOOOOOOOOOOOOOOOOOOOOOOOOOOOOOOOOOOOOOOOOOOOOOOOOOOOOOOOOOOOO | OOOOOOOOOOOOOOOOOOOOOOOOOOOOOOOOOOOOOOOOOOOOOOOOOOOOOOOOOOOOOOOOOOOOOOOOOOOOOOOOOOOOOOOOOO | OOOOOOOOOOOOOOOOOOOOOOOOOOOOOOOOOOOOOOOOOOOOOOOOOOOOOOOOOOOOOOOOOOOOOOOOOOOOOOOOOOOOOOOOOO | OOOOOOOOOOOOOOOOOOOOOOOOOOOOOOOOOOOOOOOOOOOOOOOOOOOOOOOOOOOOOOOOOOOOOOOOOOOOOOOOOOOOOOOOOO | OOOOOOOOOOOOOOOOOOOOOOOOOOOOOOOOOOOOOOOOOOOOOOOOOOOOOOOOOOOOOOOOOOOOOOOOOOOOOOOOOOOOOOOOOO | OOOOOOOOOOOOOOOOOOOOOOOOOOOOOOOOOOOOOOOOOOOOOOOOOOOOOOOOOOOOOOOOOOOOOOOOOOOOOOOOOOOOOOOOOO | OOOOOOOOOOOOOOOOOOOOOOOOOOOOOOOOOOOOOOOOOOOOOOOOOOOOOOOOOOOOOOOOOOOOOOOOOOOOOOOOOOOOOOOOOO | OOOOOOOOOOOOOOOOOOOOOOOOOOOOOOOOOOOOOOOOOOOOOOOOOOOOOOOOOOOOOOOOOOOOOOOOOOOOOOOOOOOOOOOOOO | OOOOOOOOOOOOOOOOOOOOOOOOOOOOOOOOOOOOOOOOOOOOOOOOOOOOOOOOOOOOOOOOOOOOOOOOOOOOOOOOOOOOOOOOOO |
| Master Materials Change |  |  |  |  |  |  |  |  |  |
| Item | Foxconn P/N | Orig._Usage | New_Usage | Part Description | Manufacturer Full Name | Manufacturer P/N | RoHS | Location | Sheet |
| 1 | 620101T02-015-G | 164 | 142 | CAP,100nF,+/-10%,X7R,16V,G,SMD0402 | MURATA ELEC. NORTH AMERICA | GRM155R71C104K | Y | (+)C2270 (-)C2142,C2144,C2146,C2148,C2179,C2180,C2181,C2182,C2183,C2184,C2185,C2186,C2187,C2188,C2189,C2190,C2191,C2192,C2193,C2194,C2195,C2196,C2197 | PWA BOM |
|  | 620101T00-012-G |  |  | CAP,100nF,+/-10%,X7R,16V,G,SMD0402 | WALSIN | 0402B104K160CT |  |  | PWA BOM |
|  | 620101T00-026-G |  |  | CAP,100nF,+/-10%,X7R,16V,G,SMD0402 | SAMSUNG SEMICONDUCTOR | CL05B104KO5NNNC |  |  | PWA BOM |
|  | 620101T00-015-G |  |  | CAP,100nF,+/-10%,X7R,16V,G,SMD0402 | MURATA ELEC. NORTH AMERICA | GRM155R71C104KA88D |  |  | PWA BOM |
| 2 | 15-91-2065 | 0 | 1 | CONN,Header,Pin Header,1X6,Bla,2.54mm,10u,G,SMD-6 | MOLEX INCORPORATED | 15-91-2065 |  | (+)J_CPLD_JTAG | PWA BOM |
| 3 | 71020NS00-967-G | 1 | 2 | OSC,25MHz,+/-25ppm,3.3V,15pF,G,SMD | SaRonix-eCERA Corporation | FK2500025 |  | (+)OSC2 | PWA BOM |
|  | 710209J00-100-G |  |  | OSC,25MHz,+/-25ppm,3.3V,15pF,G,SMD | TXC CORPORATION | 7X25000008 |  |  | PWA BOM |
| 4 | 61010LA00-017-G | 84 | 45 | RES,4.7KOhm,+/-1%,1/16W,G,SMD0402 | KOA SPEER ELECTRONICS, INC. | RK73H1ETTP4701F | N | (-)R1831,R1832,R1834,R1835,R1837,R1838,R1840,R1841,R1843,R1844,R1846,R1847,R1849,R1850,R1852,R1853,R1855,R1856,R1858,R1859,R1861,R1862,R1864,R1865,R1867,R1868,R1870,R1871,R1873,R1874,R1876,R1877,R1879,R1880,R1882,R1883,R1885,R1886,R2065 | PWA BOM |
|  | 61010LA00-012-G |  |  | RES,4.7KOhm,+/-1%,1/16W,G,SMD0402 | WALSIN | WR04X4701FTL |  |  | PWA BOM |
|  | 61010LA00-011-G |  |  | RES,4.7KOhm,+/-1%,1/16W,G,SMD0402 | YAGEO | RC0402FR-074K7L |  |  | PWA BOM |
|  | 61010LA00-044-G |  |  | RES,4.7KOhm,+/-1%,1/16W,G,SMD0402 | TA-I | RM04FTN4701 |  |  | PWA BOM |
| 5 | 610107A00-017-G | 120 | 121 | RES,0 Ohm,+/-5%,1/16W,G,SMD0402 | KOA SPEER ELECTRONICS, INC. | RK73Z1ETTP | N | (+)PSRR8,R2085,R2086 (-)R2068,R2069 | PWA BOM |
|  | 610107A00-012-G |  |  | RES,0 Ohm,+/-5%,1/16W,G,SMD0402 | WALSIN | WR04X000PTL |  |  | PWA BOM |
|  | 610107A00-011-G |  |  | RES,0 Ohm,+/-5%,1/16W,G,SMD0402 | YAGEO | RC0402JR-070RL |  |  | PWA BOM |
|  | 610107A00-044-G |  |  | RES,0 Ohm,+/-5%,1/16W,G,SMD0402 | TA-I | RM04JTN0 |  |  | PWA BOM |
|  | 610107A00-024-G |  |  | RES,0 Ohm,+/-5%,1/16W,G,SMD0402 | PANASONIC INDUSTRIAL CO.,LTD. | ERJ2GE0R00X |  |  | PWA BOM |
|  | 610107A00-029-G |  |  | RES,0 Ohm,+/-5%,1/16W,G,SMD0402 | VISHAY ENTER TECHNO LOGY.INC | CRCW04020000Z0ED |  |  | PWA BOM |
| 6 | 61011H500-017-G | 30 | 12 | RES,22 Ohm,+/-1%,1/16W,G,SMD0402 | KOA SPEER ELECTRONICS, INC. | RK73H1ETTP22R0F | N | (+)R2148 (-)R1833,R1836,R1839,R1842,R1845,R1848,R1851,R1854,R1857,R1860,R1863,R1866,R1869,R1872,R1875,R1878,R1881,R1884,R1887 | PWA BOM |
|  | 61011H500-012-G |  |  | RES,22 Ohm,+/-1%,1/16W,G,SMD0402 | WALSIN | WR04X22R0FTL |  |  | PWA BOM |
|  | 61011H500-011-G |  |  | RES,22 Ohm,+/-1%,1/16W,G,SMD0402 | YAGEO | RC0402FR-0722RL |  |  | PWA BOM |
|  | 61011H500-044-G |  |  | RES,22 Ohm,+/-1%,1/16W,G,SMD0402 | TA-I | RM04FTN22R0 |  |  | PWA BOM |
|  | 61011H500-024-G |  |  | RES,22 Ohm,+/-1%,1/16W,G,SMD0402 | PANASONIC INDUSTRIAL CO.,LTD. | ERJ2RKF22R0X |  |  | PWA BOM |
| 7 | 610107B00-017-G | 152 | 173 | RES,4.7KOhm,+/-5%,1/16W,G,SMD0402 | KOA SPEER ELECTRONICS, INC. | RK73B1ETTP472J | N | (+)R2128,R2129,R2130,R2131,R2132,R2133,R2134,R2135,R2136,R2137,R2138,R2139,R2140,R2141,R2142,R2143,R2144,R2145,R2146,R2147,R2149 | PWA BOM |
|  | 610107B00-012-G |  |  | RES,4.7KOhm,+/-5%,1/16W,G,SMD0402 | WALSIN | WR04X472JTL |  |  | PWA BOM |
|  | 610107B00-011-G |  |  | RES,4.7KOhm,+/-5%,1/16W,G,SMD0402 | YAGEO | RC0402JR-074K7L |  |  | PWA BOM |
|  | 610107B00-044-G |  |  | RES,4.7KOhm,+/-5%,1/16W,G,SMD0402 | TA-I | RM04JTN472 |  |  | PWA BOM |
|  | 610107B00-024-G |  |  | RES,4.7KOhm,+/-5%,1/16W,G,SMD0402 | PANASONIC INDUSTRIAL CO.,LTD. | ERJ2GEJ472X |  |  | PWA BOM |
|  | 610107B00-029-G |  |  | RES,4.7KOhm,+/-5%,1/16W,G,SMD0402 | VISHAY ENTER TECHNO LOGY.INC | CRCW04024K70JNED |  |  | PWA BOM |
| 8 | 61100LQ00-017-G | 48 | 44 | RES,20KOhm,+/-1%,1/16W,G,SMD0402 | KOA SPEER ELECTRONICS, INC. | RN731ETTP2002F50 |  | (-)R1562,R1564,R1566,R1568 | PWA BOM |
|  | 61100LQ00-012-G |  |  | RES,20KOhm,+/-1%,1/16W,G,SMD0402 | WALSIN | WF04T2002FTL |  |  | PWA BOM |
|  | 61100LQ00-011-G |  |  | RES,20KOhm,+/-1%,1/16W,G,SMD0402 | YAGEO | RT0402FRE0720KL |  |  | PWA BOM |
|  | 61100LQ00-044-G |  |  | RES,20KOhm,+/-1%,1/16W,G,SMD0402 | TA-I | RB04FTS2002 |  |  | PWA BOM |
| 9 | 610113A00-017-G | 48 | 24 | RES,2.2 Ohm,+/-5%,1/2W,G,SMD1210 | KOA SPEER ELECTRONICS, INC. | RK73B2ETTD2R2J | N | (-)R875,R877,R879,R881,R883,R885,R887,R889,R891,R893,R895,R897,R899,R901,R903,R905,R907,R909,R911,R913,R915,R917,R919,R921 | PWA BOM |
|  | 610113A00-012-G |  |  | RES,2.2 Ohm,+/-5%,1/2W,G,SMD1210 | WALSIN TECHNOLOGY CORPORATION | WF10P2R2JTL |  |  | PWA BOM |
|  | 610113A00-011-G |  |  | RES,2.2 Ohm,+/-5%,1/2W,G,SMD1210 | YAGEO CORPORATION COMPONENT | RC1210JR-072R2L |  |  | PWA BOM |
| 10 | 61015K700-017-G | 0 | 24 | RES,3.3 Ohm,+/-5%,1/2W,G,SMD1210 | KOA SPEER ELECTRONICS, INC. | RK73B2ETTD3R3J |  | (+)R875,R877,R879,R881,R883,R885,R887,R889,R891,R893,R895,R897,R899,R901,R903,R905,R907,R909,R911,R913,R915,R917,R919,R921 | PWA BOM |
| 11 | 21050RJ00-217-G | 0 | 1 | IC,IDT,9FGL0651BKILFT,G,VFQFPN-40,SMD | INTEGRATED DEVICE TECHNOLOGY | 9FGL0651BKILFT |  | (+)U29 | PWA BOM |
| 12 | 310501200-183-G | 20 | 1 | IC,Buffer,SN74LVC1G07DCKR,1.65~5.5V,G,SC70-5,SMD | TEXAS INSTRUMENTS | SN74LVC1G07DCKR | N | (-)U229,U230,U231,U232,U233,U234,U235,U236,U237,U238,U239,U240,U241,U242,U243,U244,U245,U246,U247 | PWA BOM |
| 13 | 2A5910Q00-HYM-G | 0 | 10 | SMT NUT,CARBON STEEL,G,FIVETECH,82-059-01-022-01-RL | Fivetech Technology Inc. | 82-059-01-022-01-RL |  | (+)H1,H2,H3,H4,H7,H8,H9,H10,H30,H31 | PWA BOM |
| 14 | 620106200-015-G | 1 | 0 | CAP,10nF,+/-10%,X7R,16V,G,SMD0402 | MURATA ELEC. NORTH AMERICA | GRM155R71C103K | N | (-)C2267 | PWA BOM |
|  | 620106200-012-G |  |  | CAP,10nF,+/-10%,X7R,16V,G,SMD0402 | WALSIN | 0402B103K160CT |  |  | PWA BOM |
|  | 620106200-026-G |  |  | CAP,10nF,+/-10%,X7R,16V,G,SMD0402 | SAMSUNG | CL05B103KO5NNNC |  |  | PWA BOM |
|  | 620106200-023-G |  |  | CAP,10nF,+/-10%,X7R,16V,G,SMD0402 | TAIYO | EMK105B7103KV-F |  |  | PWA BOM |
| 15 | 610115J00-017-G | 1 | 0 | RES,33 Ohm,+/-1%,1/16W,G,SMD0402 | KOA SPEER ELECTRONICS, INC. | RK73H1ETTP33R0F | N | (-)R315 | PWA BOM |
|  | 610115J00-012-G |  |  | RES,33 Ohm,+/-1%,1/16W,G,SMD0402 | WALSIN | WR04X33R0FTL |  |  | PWA BOM |
|  | 610115J00-011-G |  |  | RES,33 Ohm,+/-1%,1/16W,G,SMD0402 | YAGEO | RC0402FR-0733RL |  |  | PWA BOM |
|  | 610115J00-044-G |  |  | RES,33 Ohm,+/-1%,1/16W,G,SMD0402 | TA-I | RM04FTN33R0 |  |  | PWA BOM |
|  | 610115J00-024-G |  |  | RES,33 Ohm,+/-1%,1/16W,G,SMD0402 | PANASONIC INDUSTRIAL CO.,LTD. | ERJ2RKF33R0X |  |  | PWA BOM |
| 16 | 71020SH00-107-G | 1 | 0 | OSC,25MHz,+/-25ppm,3.3V,15pF,G,SMD | DAISHINKU CORPORATION/DAISHINKU SINGAPORE PTE LTD/KDS | 1XSE025000AR122 |  | (-)Y3 | PWA BOM |
| 17 | 3406B0G00-309-G | 1 | 0 | CONN,Header,Pin Header,2X5,V/T,Bla,2.54mm,10u,G,SMD-10 | SAMTEC INC. | TSM-105-04-L-DV-A-P-TR |  | (-)J_CPLD_JTAG | PWA BOM |
| 18 | 9FGL0651BKILFT | 1 | 0 | IC,IDT,9FGL0651BKILFT,G,VFQFN-40,SMD | INTEGRATED DEVICE TECHNOLOGY | 9FGL0651BKILFT |  | (-)U29 | PWA BOM |
| OOOOOOOOOOOOOOOOOOOOOOOOOOOOOOOOOOOOOOOOOOOOOOOOOOOOOOOOOOOOOOOOOOOOOOOOOOOOOOOOOOOOOOOOOO | OOOOOOOOOOOOOOOOOOOOOOOOOOOOOOOOOOOOOOOOOOOOOOOOOOOOOOOOOOOOOOOOOOOOOOOOOOOOOOOOOOOOOOOOOO | OOOOOOOOOOOOOOOOOOOOOOOOOOOOOOOOOOOOOOOOOOOOOOOOOOOOOOOOOOOOOOOOOOOOOOOOOOOOOOOOOOOOOOOOOO | OOOOOOOOOOOOOOOOOOOOOOOOOOOOOOOOOOOOOOOOOOOOOOOOOOOOOOOOOOOOOOOOOOOOOOOOOOOOOOOOOOOOOOOOOO | OOOOOOOOOOOOOOOOOOOOOOOOOOOOOOOOOOOOOOOOOOOOOOOOOOOOOOOOOOOOOOOOOOOOOOOOOOOOOOOOOOOOOOOOOO | OOOOOOOOOOOOOOOOOOOOOOOOOOOOOOOOOOOOOOOOOOOOOOOOOOOOOOOOOOOOOOOOOOOOOOOOOOOOOOOOOOOOOOOOOO | OOOOOOOOOOOOOOOOOOOOOOOOOOOOOOOOOOOOOOOOOOOOOOOOOOOOOOOOOOOOOOOOOOOOOOOOOOOOOOOOOOOOOOOOOO | OOOOOOOOOOOOOOOOOOOOOOOOOOOOOOOOOOOOOOOOOOOOOOOOOOOOOOOOOOOOOOOOOOOOOOOOOOOOOOOOOOOOOOOOOO | OOOOOOOOOOOOOOOOOOOOOOOOOOOOOOOOOOOOOOOOOOOOOOOOOOOOOOOOOOOOOOOOOOOOOOOOOOOOOOOOOOOOOOOOOO |  |
| TLA Parts Change |  |  |  |  |  |  |  |  |  |
| Item | Foxconn P/N | Qty | Part Description | Manufacturer Full Name | Manufacturer P/N | RoHS | Location | Remark |  |
| 1 | 1B51GF500-600-G | 1 | 8_MYLAR_HDD_BP_FRONT_POWER9 | 1B51GF500-600-G | 1B51GF500-600-G | G |  | In New BOM |  |
| BOM Change List Date:Sat May 27 11:49:03 GMT+08:00 2017 |  |  |  |  |  |  |  |  |  |
| New BOM file : C:\<user>\Barreleye_G2-Tri-mode BPX24-EVT-X00-BOM-X03_20170526.xls |  |  |  |  |  |  |  |  |  |
| Old BOM file : C:\<user>\Barreleye_G2-Tri-mode BPX24-EVT-X00-BOM-X02_20170517_for 2nd source.xls |  |  |  |  |  |  |  |  |  |
| ##### Add Parts |  |  |  |  |  |  |  |  |  |
| Item | Location | Qty | Foxconn P/N | Part Description | Manufacturer Full Name | Manufacturer P/N | RoHS | Sheet |  |
| 1 | C397 | 1 | 620101T02-015-G | CAP,100nF,+/-10%,X7R,16V,G,SMD0402 | MURATA ELEC. NORTH AMERICA | GRM155R71C104K | Y | PWA BOM |  |
|  |  |  | 620101T00-012-G | CAP,100nF,+/-10%,X7R,16V,G,SMD0402 | WALSIN | 0402B104K160CT |  | PWA BOM |  |
|  |  |  | 620101T00-026-G | CAP,100nF,+/-10%,X7R,16V,G,SMD0402 | SAMSUNG SEMICONDUCTOR | CL05B104KO5NNNC |  | PWA BOM |  |
|  |  |  | 620101T00-015-G | CAP,100nF,+/-10%,X7R,16V,G,SMD0402 | MURATA ELEC. NORTH AMERICA | GRM155R71C104KA88D |  | PWA BOM |  |
| 2 | R229,R230,R251,R252 | 4 | 61010LA00-017-G | RES,4.7KOhm,+/-1%,1/16W,G,SMD0402 | KOA SPEER ELECTRONICS, INC. | RK73H1ETTP4701F | N | PWA BOM |  |
|  |  |  | 61010LA00-012-G | RES,4.7KOhm,+/-1%,1/16W,G,SMD0402 | WALSIN | WR04X4701FTL |  | PWA BOM |  |
|  |  |  | 61010LA00-011-G | RES,4.7KOhm,+/-1%,1/16W,G,SMD0402 | YAGEO | RC0402FR-074K7L |  | PWA BOM |  |
|  |  |  | 61010LA00-044-G | RES,4.7KOhm,+/-1%,1/16W,G,SMD0402 | TA-I | RM04FTN4701 |  | PWA BOM |  |
| 3 | R228 | 1 | 610107B00-017-G | RES,4.7KOhm,+/-5%,1/16W,G,SMD0402 | KOA SPEER ELECTRONICS, INC. | RK73B1ETTP472J | N | PWA BOM |  |
|  |  |  | 610107B00-012-G | RES,4.7KOhm,+/-5%,1/16W,G,SMD0402 | WALSIN | WR04X472JTL |  | PWA BOM |  |
|  |  |  | 610107B00-011-G | RES,4.7KOhm,+/-5%,1/16W,G,SMD0402 | YAGEO | RC0402JR-074K7L |  | PWA BOM |  |
|  |  |  | 610107B00-044-G | RES,4.7KOhm,+/-5%,1/16W,G,SMD0402 | TA-I | RM04JTN472 |  | PWA BOM |  |
|  |  |  | 610107B00-024-G | RES,4.7KOhm,+/-5%,1/16W,G,SMD0402 | PANASONIC INDUSTRIAL CO.,LTD. | ERJ2GEJ472X |  | PWA BOM |  |
|  |  |  | 610107B00-029-G | RES,4.7KOhm,+/-5%,1/16W,G,SMD0402 | VISHAY ENTER TECHNO LOGY.INC | CRCW04024K70JNED |  | PWA BOM |  |
| 4 | U_I2C_RE2 | 1 | 311004800-031-G | IC,Translator,PCA9617ADPJ,0.8~5.5V,2.2~5.5V,G,TSSOP-8,SMD | NXP SEMICONDUCTORS | PCA9617ADPJ |  | PWA BOM |  |
|  |  |  | 311004V00-223-G | Logic IC,Translator,PCA9617ADMR2G,Vcca=0.8V~5.5V,Vccb=2.2V~5.5V,102ns,Micro8,8P,G | ON SEMICONDUCTOR CORP | PCA9617ADMR2G |  | PWA BOM |  |
| ##### Remove Parts |  |  |  |  |  |  |  |  |  |
| Item | Location | Qty | Foxconn P/N | Part Description | Manufacturer Full Name | Manufacturer P/N | RoHS | Sheet |  |
| ##### Change Parts |  |  |  |  |  |  |  |  |  |
| Item | Location | Qty | Foxconn P/N | Part Description | Manufacturer Full Name | Manufacturer P/N | RoHS | Sheet | Remark |
| 1 | J_CPLD_JTAG | 1 | 3406B6F00-317-G | CONN,Header,WTB,2X3,R/A,Bla,2.5mm,15u,G,SMD-6 | MOLEX INCORPORATED | 15-91-2065 |  | PWA BOM | In New BOM |
|  | J_CPLD_JTAG | 1 | 15-91-2065 | CONN,Header,Pin Header,1X6,Bla,2.54mm,10u,G,SMD-6 | MOLEX INCORPORATED | 15-91-2065 |  | PWA BOM | In Old BOM |
| ##### Change Revision |  |  |  |  |  |  |  |  |  |
| Sheet | REV OF BOM | CUSTOMER | CUSTOMER P/N | PWA PN | PWA DESCRIPTION | PWA REV | DATE | Remark |  |
| OOOOOOOOOOOOOOOOOOOOOOOOOOOOOOOOOOOOOOOOOOOOOOOOOOOOOOOOOOOOOOOOOOOOOOOOOOOOOOOOOOOOOOOOOO | OOOOOOOOOOOOOOOOOOOOOOOOOOOOOOOOOOOOOOOOOOOOOOOOOOOOOOOOOOOOOOOOOOOOOOOOOOOOOOOOOOOOOOOOOO | OOOOOOOOOOOOOOOOOOOOOOOOOOOOOOOOOOOOOOOOOOOOOOOOOOOOOOOOOOOOOOOOOOOOOOOOOOOOOOOOOOOOOOOOOO | OOOOOOOOOOOOOOOOOOOOOOOOOOOOOOOOOOOOOOOOOOOOOOOOOOOOOOOOOOOOOOOOOOOOOOOOOOOOOOOOOOOOOOOOOO | OOOOOOOOOOOOOOOOOOOOOOOOOOOOOOOOOOOOOOOOOOOOOOOOOOOOOOOOOOOOOOOOOOOOOOOOOOOOOOOOOOOOOOOOOO | OOOOOOOOOOOOOOOOOOOOOOOOOOOOOOOOOOOOOOOOOOOOOOOOOOOOOOOOOOOOOOOOOOOOOOOOOOOOOOOOOOOOOOOOOO | OOOOOOOOOOOOOOOOOOOOOOOOOOOOOOOOOOOOOOOOOOOOOOOOOOOOOOOOOOOOOOOOOOOOOOOOOOOOOOOOOOOOOOOOOO | OOOOOOOOOOOOOOOOOOOOOOOOOOOOOOOOOOOOOOOOOOOOOOOOOOOOOOOOOOOOOOOOOOOOOOOOOOOOOOOOOOOOOOOOOO | OOOOOOOOOOOOOOOOOOOOOOOOOOOOOOOOOOOOOOOOOOOOOOOOOOOOOOOOOOOOOOOOOOOOOOOOOOOOOOOOOOOOOOOOOO | OOOOOOOOOOOOOOOOOOOOOOOOOOOOOOOOOOOOOOOOOOOOOOOOOOOOOOOOOOOOOOOOOOOOOOOOOOOOOOOOOOOOOOOOOO |
| Second Source Change |  |  |  |  |  |  |  |  |  |
| Item | Location | Change Type | Foxconn P/N | Part Description | Manufacturer Full Name | Manufacturer P/N | RoHS | Sheet |  |
| OOOOOOOOOOOOOOOOOOOOOOOOOOOOOOOOOOOOOOOOOOOOOOOOOOOOOOOOOOOOOOOOOOOOOOOOOOOOOOOOOOOOOOOOOO | OOOOOOOOOOOOOOOOOOOOOOOOOOOOOOOOOOOOOOOOOOOOOOOOOOOOOOOOOOOOOOOOOOOOOOOOOOOOOOOOOOOOOOOOOO | OOOOOOOOOOOOOOOOOOOOOOOOOOOOOOOOOOOOOOOOOOOOOOOOOOOOOOOOOOOOOOOOOOOOOOOOOOOOOOOOOOOOOOOOOO | OOOOOOOOOOOOOOOOOOOOOOOOOOOOOOOOOOOOOOOOOOOOOOOOOOOOOOOOOOOOOOOOOOOOOOOOOOOOOOOOOOOOOOOOOO | OOOOOOOOOOOOOOOOOOOOOOOOOOOOOOOOOOOOOOOOOOOOOOOOOOOOOOOOOOOOOOOOOOOOOOOOOOOOOOOOOOOOOOOOOO | OOOOOOOOOOOOOOOOOOOOOOOOOOOOOOOOOOOOOOOOOOOOOOOOOOOOOOOOOOOOOOOOOOOOOOOOOOOOOOOOOOOOOOOOOO | OOOOOOOOOOOOOOOOOOOOOOOOOOOOOOOOOOOOOOOOOOOOOOOOOOOOOOOOOOOOOOOOOOOOOOOOOOOOOOOOOOOOOOOOOO | OOOOOOOOOOOOOOOOOOOOOOOOOOOOOOOOOOOOOOOOOOOOOOOOOOOOOOOOOOOOOOOOOOOOOOOOOOOOOOOOOOOOOOOOOO | OOOOOOOOOOOOOOOOOOOOOOOOOOOOOOOOOOOOOOOOOOOOOOOOOOOOOOOOOOOOOOOOOOOOOOOOOOOOOOOOOOOOOOOOOO | OOOOOOOOOOOOOOOOOOOOOOOOOOOOOOOOOOOOOOOOOOOOOOOOOOOOOOOOOOOOOOOOOOOOOOOOOOOOOOOOOOOOOOOOOO |
| Master Materials Change |  |  |  |  |  |  |  |  |  |
| Item | Foxconn P/N | Orig._Usage | New_Usage | Part Description | Manufacturer Full Name | Manufacturer P/N | RoHS | Location | Sheet |
| 1 | 620101T02-015-G | 142 | 143 | CAP,100nF,+/-10%,X7R,16V,G,SMD0402 | MURATA ELEC. NORTH AMERICA | GRM155R71C104K | Y | (+)C397 | PWA BOM |
|  | 620101T00-012-G |  |  | CAP,100nF,+/-10%,X7R,16V,G,SMD0402 | WALSIN | 0402B104K160CT |  |  | PWA BOM |
|  | 620101T00-026-G |  |  | CAP,100nF,+/-10%,X7R,16V,G,SMD0402 | SAMSUNG SEMICONDUCTOR | CL05B104KO5NNNC |  |  | PWA BOM |
|  | 620101T00-015-G |  |  | CAP,100nF,+/-10%,X7R,16V,G,SMD0402 | MURATA ELEC. NORTH AMERICA | GRM155R71C104KA88D |  |  | PWA BOM |
| 2 | 61010LA00-017-G | 45 | 49 | RES,4.7KOhm,+/-1%,1/16W,G,SMD0402 | KOA SPEER ELECTRONICS, INC. | RK73H1ETTP4701F | N | (+)R229,R230,R251,R252 | PWA BOM |
|  | 61010LA00-012-G |  |  | RES,4.7KOhm,+/-1%,1/16W,G,SMD0402 | WALSIN | WR04X4701FTL |  |  | PWA BOM |
|  | 61010LA00-011-G |  |  | RES,4.7KOhm,+/-1%,1/16W,G,SMD0402 | YAGEO | RC0402FR-074K7L |  |  | PWA BOM |
|  | 61010LA00-044-G |  |  | RES,4.7KOhm,+/-1%,1/16W,G,SMD0402 | TA-I | RM04FTN4701 |  |  | PWA BOM |
| 3 | 610107B00-017-G | 173 | 174 | RES,4.7KOhm,+/-5%,1/16W,G,SMD0402 | KOA SPEER ELECTRONICS, INC. | RK73B1ETTP472J | N | (+)R228 | PWA BOM |
|  | 610107B00-012-G |  |  | RES,4.7KOhm,+/-5%,1/16W,G,SMD0402 | WALSIN | WR04X472JTL |  |  | PWA BOM |
|  | 610107B00-011-G |  |  | RES,4.7KOhm,+/-5%,1/16W,G,SMD0402 | YAGEO | RC0402JR-074K7L |  |  | PWA BOM |
|  | 610107B00-044-G |  |  | RES,4.7KOhm,+/-5%,1/16W,G,SMD0402 | TA-I | RM04JTN472 |  |  | PWA BOM |
|  | 610107B00-024-G |  |  | RES,4.7KOhm,+/-5%,1/16W,G,SMD0402 | PANASONIC INDUSTRIAL CO.,LTD. | ERJ2GEJ472X |  |  | PWA BOM |
|  | 610107B00-029-G |  |  | RES,4.7KOhm,+/-5%,1/16W,G,SMD0402 | VISHAY ENTER TECHNO LOGY.INC | CRCW04024K70JNED |  |  | PWA BOM |
| 4 | 311004800-031-G | 1 | 2 | IC,Translator,PCA9617ADPJ,0.8~5.5V,2.2~5.5V,G,TSSOP-8,SMD | NXP SEMICONDUCTORS | PCA9617ADPJ |  | (+)U_I2C_RE2 | PWA BOM |
|  | 311004V00-223-G |  |  | Logic IC,Translator,PCA9617ADMR2G,Vcca=0.8V~5.5V,Vccb=2.2V~5.5V,102ns,Micro8,8P,G | ON SEMICONDUCTOR CORP | PCA9617ADMR2G |  |  | PWA BOM |
| 5 | 3406B6F00-317-G | 0 | 1 | CONN,Header,WTB,2X3,R/A,Bla,2.5mm,15u,G,SMD-6 | MOLEX INCORPORATED | 15-91-2065 |  | (+)J_CPLD_JTAG | PWA BOM |
| 6 | 15-91-2065 | 1 | 0 | CONN,Header,Pin Header,1X6,Bla,2.54mm,10u,G,SMD-6 | MOLEX INCORPORATED | 15-91-2065 |  | (-)J_CPLD_JTAG | PWA BOM |
| OOOOOOOOOOOOOOOOOOOOOOOOOOOOOOOOOOOOOOOOOOOOOOOOOOOOOOOOOOOOOOOOOOOOOOOOOOOOOOOOOOOOOOOOOO | OOOOOOOOOOOOOOOOOOOOOOOOOOOOOOOOOOOOOOOOOOOOOOOOOOOOOOOOOOOOOOOOOOOOOOOOOOOOOOOOOOOOOOOOOO | OOOOOOOOOOOOOOOOOOOOOOOOOOOOOOOOOOOOOOOOOOOOOOOOOOOOOOOOOOOOOOOOOOOOOOOOOOOOOOOOOOOOOOOOOO | OOOOOOOOOOOOOOOOOOOOOOOOOOOOOOOOOOOOOOOOOOOOOOOOOOOOOOOOOOOOOOOOOOOOOOOOOOOOOOOOOOOOOOOOOO | OOOOOOOOOOOOOOOOOOOOOOOOOOOOOOOOOOOOOOOOOOOOOOOOOOOOOOOOOOOOOOOOOOOOOOOOOOOOOOOOOOOOOOOOOO | OOOOOOOOOOOOOOOOOOOOOOOOOOOOOOOOOOOOOOOOOOOOOOOOOOOOOOOOOOOOOOOOOOOOOOOOOOOOOOOOOOOOOOOOOO | OOOOOOOOOOOOOOOOOOOOOOOOOOOOOOOOOOOOOOOOOOOOOOOOOOOOOOOOOOOOOOOOOOOOOOOOOOOOOOOOOOOOOOOOOO | OOOOOOOOOOOOOOOOOOOOOOOOOOOOOOOOOOOOOOOOOOOOOOOOOOOOOOOOOOOOOOOOOOOOOOOOOOOOOOOOOOOOOOOOOO | OOOOOOOOOOOOOOOOOOOOOOOOOOOOOOOOOOOOOOOOOOOOOOOOOOOOOOOOOOOOOOOOOOOOOOOOOOOOOOOOOOOOOOOOOO |  |
| TLA Parts Change |  |  |  |  |  |  |  |  |  |
| Item | Foxconn P/N | Qty | Part Description | Manufacturer Full Name | Manufacturer P/N | RoHS | Location | Remark |  |
| 1 | 7J-004-938 | 1 | L6 LABEL ( 12.7*11.1mm) | FOXCONN / EPD1 | 7J-004-938 | G |  | In Old BOM |  |
| 2 | 1B51GF500-600-G | 1 | 8_MYLAR_HDD_BP_FRONT_POWER9 | 1B51GF500-600-G | 1B51GF500-600-G | G |  | In Old BOM |  |
| BOM Change List Date:Mon Jun 05 11:17:13 GMT+08:00 2017 |  |  |  |  |  |  |  |  |  |
| New BOM file : C:\Barreleye_G2-Tri-mode BPX24-EVT-X00-BOM-X03_20170605_Final.xls |  |  |  |  |  |  |  |  |  |
| Old BOM file : C:\Barreleye_G2-Tri-mode BPX24-EVT-X00-BOM-X03_20170602_Final.xls |  |  |  |  |  |  |  |  |  |
| ##### Add Parts |  |  |  |  |  |  |  |  |  |
| Item | Location | Qty | Foxconn P/N | Part Description | Manufacturer Full Name | Manufacturer P/N | RoHS | Sheet |  |
| ##### Remove Parts |  |  |  |  |  |  |  |  |  |
| Item | Location | Qty | Foxconn P/N | Part Description | Manufacturer Full Name | Manufacturer P/N | RoHS | Sheet |  |
| ##### Change Parts |  |  |  |  |  |  |  |  |  |
| Item | Location | Qty | Foxconn P/N | Part Description | Manufacturer Full Name | Manufacturer P/N | RoHS | Sheet | Remark |
| 1 | C2198,C2208,C2209,C2210,C2211,C2212,C2213,C2214,C2215,C2216,C2217,C2218,C2219,C2220,C2221,C2222,C2223,C2224 | 18 | 62011LU00-015-G | CAP,100nF,+/-10%,X5R,16V,G,SMD0402 | MURATA ELEC. NORTH AMERICA | GRM155R61C104KA88D | G | PWA BOM | In New BOM |
|  |  |  | 620100300-023-G | CAP,100nF,+/-10%,X5R,16V,G,SMD0402 | TAIYO | EMK105BJ104KV-F | G | PWA BOM | In New BOM |
|  |  |  | 620100300-026-G | CAP,100nF,+/-10%,X5R,16V,G,SMD0402 | SAMSUNG SEMICONDUCTOR | CL05A104KO5NNNC | G | PWA BOM | In New BOM |
|  |  |  | 620100300-012-G | CAP,100nF,+/-10%,X5R,16V,G,SMD0402 | WALSIN TECHNOLOGY CORPORATION | 0402X104K160CT | G | PWA BOM | In New BOM |
|  | C2198,C2208,C2209,C2210,C2211,C2212,C2213,C2214,C2215,C2216,C2217,C2218,C2219,C2220,C2221,C2222,C2223,C2224 | 18 | 62011LU00-015-G | CAP,100nF,+/-10%,X5R,16V,G,SMD0402 | MURATA ELEC. NORTH AMERICA | GRM155R61C104KA88D | G | PWA BOM | In Old BOM |
|  |  |  | 620100300-023-G | CAP,100nF,+/-10%,X5R,16V,G,SMD0402 | TAIYO | EMK105BJ104KV-F | G | PWA BOM | In Old BOM |
|  |  |  | 620100300-026-G | CAP,100nF,+/-10%,X5R,16V,G,SMD0402 | SAMSUNG | CL05A104KO5NNNC | G | PWA BOM | In Old BOM |
|  |  |  | 620100300-012-G | CAP,100nF,+/-10%,X5R,16V,G,SMD0402 | WALSIN TECHNOLOGY CORPORATION | 0402X104K160CT | G | PWA BOM | In Old BOM |
| 2 | L1 | 1 | 720101900-015-G | FB,60 Ohm@100MHz,+/-25%,3A,25mOhm,G,SMD0805 | MURATA ELEC. NORTH AMERICA | BLM21PG600SN1D | G | PWA BOM | In New BOM |
|  |  |  | 720101900-026-G | FB,60 Ohm@100MHz,+/-25%,3A,25mOhm,G,SMD0805 | SAMSUNG SEMICONDUCTOR | CIC21P600NE | G | PWA BOM | In New BOM |
|  | L1 | 1 | 720101900-015-G | FB,60 Ohm@100MHz,+/-25%,3A,25mOhm,G,SMD0805 | MURATA ELEC. NORTH AMERICA | BLM21PG600SN1D | G | PWA BOM | In Old BOM |
|  |  |  | 720101900-026-G | FB,60 Ohm@100MHz,+/-25%,3A,25mOhm,G,SMD0805 | SAMSUNG | CIC21P600NE | G | PWA BOM | In Old BOM |
| 3 | PCB | 1 | 0101F2800-000-G | PCB,Zaius-Tri-mode BPX24 EVT-X00,OSP,Red,22L,21.122*3.470,G | GOLD CIRCUIT ELECTRONICS LTD. | 0101F2800-000-G | G | PWA BOM | In New BOM |
|  |  |  | 0101F2800-000-G | PCB,Zaius-Tri-mode BPX24 EVT-X00,OSP,Red,22L,21.122*3.470,G | ZHUHAI FOUNDER PRINTED CIRCUIT BOARD（HK） DEVELOPMENT LIMITED | 0101F2800-000-G | G | PWA BOM | In New BOM |
|  | PCB | 1 | PCB | PCB | PCB | PCB | G | PWA BOM | In Old BOM |
| ##### Change Revision |  |  |  |  |  |  |  |  |  |
| Sheet | REV OF BOM | CUSTOMER | CUSTOMER P/N | PWA PN | PWA DESCRIPTION | PWA REV | DATE | Remark |  |
| OOOOOOOOOOOOOOOOOOOOOOOOOOOOOOOOOOOOOOOOOOOOOOOOOOOOOOOOOOOOOOOOOOOOOOOOOOOOOOOOOOOOOOOOOO | OOOOOOOOOOOOOOOOOOOOOOOOOOOOOOOOOOOOOOOOOOOOOOOOOOOOOOOOOOOOOOOOOOOOOOOOOOOOOOOOOOOOOOOOOO | OOOOOOOOOOOOOOOOOOOOOOOOOOOOOOOOOOOOOOOOOOOOOOOOOOOOOOOOOOOOOOOOOOOOOOOOOOOOOOOOOOOOOOOOOO | OOOOOOOOOOOOOOOOOOOOOOOOOOOOOOOOOOOOOOOOOOOOOOOOOOOOOOOOOOOOOOOOOOOOOOOOOOOOOOOOOOOOOOOOOO | OOOOOOOOOOOOOOOOOOOOOOOOOOOOOOOOOOOOOOOOOOOOOOOOOOOOOOOOOOOOOOOOOOOOOOOOOOOOOOOOOOOOOOOOOO | OOOOOOOOOOOOOOOOOOOOOOOOOOOOOOOOOOOOOOOOOOOOOOOOOOOOOOOOOOOOOOOOOOOOOOOOOOOOOOOOOOOOOOOOOO | OOOOOOOOOOOOOOOOOOOOOOOOOOOOOOOOOOOOOOOOOOOOOOOOOOOOOOOOOOOOOOOOOOOOOOOOOOOOOOOOOOOOOOOOOO | OOOOOOOOOOOOOOOOOOOOOOOOOOOOOOOOOOOOOOOOOOOOOOOOOOOOOOOOOOOOOOOOOOOOOOOOOOOOOOOOOOOOOOOOOO | OOOOOOOOOOOOOOOOOOOOOOOOOOOOOOOOOOOOOOOOOOOOOOOOOOOOOOOOOOOOOOOOOOOOOOOOOOOOOOOOOOOOOOOOOO | OOOOOOOOOOOOOOOOOOOOOOOOOOOOOOOOOOOOOOOOOOOOOOOOOOOOOOOOOOOOOOOOOOOOOOOOOOOOOOOOOOOOOOOOOO |
| Second Source Change |  |  |  |  |  |  |  |  |  |
| Item | Location | Change Type | Foxconn P/N | Part Description | Manufacturer Full Name | Manufacturer P/N | RoHS | Sheet |  |
| OOOOOOOOOOOOOOOOOOOOOOOOOOOOOOOOOOOOOOOOOOOOOOOOOOOOOOOOOOOOOOOOOOOOOOOOOOOOOOOOOOOOOOOOOO | OOOOOOOOOOOOOOOOOOOOOOOOOOOOOOOOOOOOOOOOOOOOOOOOOOOOOOOOOOOOOOOOOOOOOOOOOOOOOOOOOOOOOOOOOO | OOOOOOOOOOOOOOOOOOOOOOOOOOOOOOOOOOOOOOOOOOOOOOOOOOOOOOOOOOOOOOOOOOOOOOOOOOOOOOOOOOOOOOOOOO | OOOOOOOOOOOOOOOOOOOOOOOOOOOOOOOOOOOOOOOOOOOOOOOOOOOOOOOOOOOOOOOOOOOOOOOOOOOOOOOOOOOOOOOOOO | OOOOOOOOOOOOOOOOOOOOOOOOOOOOOOOOOOOOOOOOOOOOOOOOOOOOOOOOOOOOOOOOOOOOOOOOOOOOOOOOOOOOOOOOOO | OOOOOOOOOOOOOOOOOOOOOOOOOOOOOOOOOOOOOOOOOOOOOOOOOOOOOOOOOOOOOOOOOOOOOOOOOOOOOOOOOOOOOOOOOO | OOOOOOOOOOOOOOOOOOOOOOOOOOOOOOOOOOOOOOOOOOOOOOOOOOOOOOOOOOOOOOOOOOOOOOOOOOOOOOOOOOOOOOOOOO | OOOOOOOOOOOOOOOOOOOOOOOOOOOOOOOOOOOOOOOOOOOOOOOOOOOOOOOOOOOOOOOOOOOOOOOOOOOOOOOOOOOOOOOOOO | OOOOOOOOOOOOOOOOOOOOOOOOOOOOOOOOOOOOOOOOOOOOOOOOOOOOOOOOOOOOOOOOOOOOOOOOOOOOOOOOOOOOOOOOOO | OOOOOOOOOOOOOOOOOOOOOOOOOOOOOOOOOOOOOOOOOOOOOOOOOOOOOOOOOOOOOOOOOOOOOOOOOOOOOOOOOOOOOOOOOO |
| Master Materials Change |  |  |  |  |  |  |  |  |  |
| Item | Foxconn P/N | Orig._Usage | New_Usage | Part Description | Manufacturer Full Name | Manufacturer P/N | RoHS | Location | Sheet |
| 1 | 0101F2800-000-G | 0 | 1 | PCB,Zaius-Tri-mode BPX24 EVT-X00,OSP,Red,22L,21.122*3.470,G | GOLD CIRCUIT ELECTRONICS LTD. | 0101F2800-000-G | G | (+)PCB | PWA BOM |
|  | 0101F2800-000-G |  |  | PCB,Zaius-Tri-mode BPX24 EVT-X00,OSP,Red,22L,21.122*3.470,G | ZHUHAI FOUNDER PRINTED CIRCUIT BOARD（HK） DEVELOPMENT LIMITED | 0101F2800-000-G |  |  | PWA BOM |
| 2 | PCB | 1 | 0 | PCB | PCB | PCB | G | (-)PCB | PWA BOM |
| OOOOOOOOOOOOOOOOOOOOOOOOOOOOOOOOOOOOOOOOOOOOOOOOOOOOOOOOOOOOOOOOOOOOOOOOOOOOOOOOOOOOOOOOOO | OOOOOOOOOOOOOOOOOOOOOOOOOOOOOOOOOOOOOOOOOOOOOOOOOOOOOOOOOOOOOOOOOOOOOOOOOOOOOOOOOOOOOOOOOO | OOOOOOOOOOOOOOOOOOOOOOOOOOOOOOOOOOOOOOOOOOOOOOOOOOOOOOOOOOOOOOOOOOOOOOOOOOOOOOOOOOOOOOOOOO | OOOOOOOOOOOOOOOOOOOOOOOOOOOOOOOOOOOOOOOOOOOOOOOOOOOOOOOOOOOOOOOOOOOOOOOOOOOOOOOOOOOOOOOOOO | OOOOOOOOOOOOOOOOOOOOOOOOOOOOOOOOOOOOOOOOOOOOOOOOOOOOOOOOOOOOOOOOOOOOOOOOOOOOOOOOOOOOOOOOOO | OOOOOOOOOOOOOOOOOOOOOOOOOOOOOOOOOOOOOOOOOOOOOOOOOOOOOOOOOOOOOOOOOOOOOOOOOOOOOOOOOOOOOOOOOO | OOOOOOOOOOOOOOOOOOOOOOOOOOOOOOOOOOOOOOOOOOOOOOOOOOOOOOOOOOOOOOOOOOOOOOOOOOOOOOOOOOOOOOOOOO | OOOOOOOOOOOOOOOOOOOOOOOOOOOOOOOOOOOOOOOOOOOOOOOOOOOOOOOOOOOOOOOOOOOOOOOOOOOOOOOOOOOOOOOOOO | OOOOOOOOOOOOOOOOOOOOOOOOOOOOOOOOOOOOOOOOOOOOOOOOOOOOOOOOOOOOOOOOOOOOOOOOOOOOOOOOOOOOOOOOOO | OOOOOOOOOOOOOOOOOOOOOOOOOOOOOOOOOOOOOOOOOOOOOOOOOOOOOOOOOOOOOOOOOOOOOOOOOOOOOOOOOOOOOOOOOO |
| TLA Parts Change |  |  |  |  |  |  |  |  |  |
| Item | Foxconn P/N | Qty | Part Description | Manufacturer Full Name | Manufacturer P/N | RoHS | Location | Remark | BOM |
| 1 | 1B51GF500-600-G 1B51KUN00-600-G | 1 | 8_MYLAR_HDD_BP_FRONT_POWER9 8_MYLAR-HDD-BP-FRONT_BG2 | FOXCONN / EPD5 | 1B51GF500-600-G  1B51KUN00-600-G | G |  | Rev.X02 Rev.X01 | In New BOM |
|  | 1B51GF500-600-G 1B51KUN00-600-G | 1 | 8_MYLAR_HDD_BP_FRONT_POWER9 | FOXCONN / EPD5 | 1B51GF500-600-G | G |  | Rev.X02 | In Old BOM |
| BOM Change List Date:Fri Aug 25 09:36:54 CST 2017 |  |  |  |  |  |  |  |  |  |
| New BOM file : E:\barreleye g2\0824\foxbis\new BOM\BPX24 25.xls |  |  |  |  |  |  |  |  |  |
| Old BOM file : E:\barreleye g2\0824\foxbis\old bom\Barreleye_G2-Tri-mode BPX24-EVT-X00-BOM-X03_20170605_Final.xls |  |  |  |  |  |  |  |  |  |
| ##### Add Parts |  |  |  |  |  |  |  |  |  |
| Item | Location | Qty | Foxconn P/N | Part Description | Manufacturer Full Name | Manufacturer P/N | RoHS | Sheet |  |
| ##### Remove Parts |  |  |  |  |  |  |  |  |  |
| Item | Location | Qty | Foxconn P/N | Part Description | Manufacturer Full Name | Manufacturer P/N | RoHS | Sheet |  |
| ##### Change Parts |  |  |  |  |  |  |  |  |  |
| Item | Location | Qty | Foxconn P/N | Part Description | Manufacturer Full Name | Manufacturer P/N | RoHS | Sheet | Remark |
| 1 | PSTL2,PFTL2,PETL2 | 3 | 630341400-088-G | IND,22nH@1MHz,+/-20%,19A,368uOhm,SHLD,G,SMD | COOPER BUSSMANN, INC. | FP0404R1-R022-R | G | PWA BOM | In New BOM |
|  |  |  | 630362G00-065-G | 22nH@100KHz,+/-20%,19A,0.32mOhm,SHLD,G,SMD | Delta | HCB0430-220 | G | PWA BOM | In New BOM |
|  | PSTL2,PFTL2,PETL2 | 3 | 630341400-088-G | IND,22nH@1MHz,+/-20%,19A,368uOhm,SHLD,G,SMD | COOPER BUSSMANN, INC. | FP0404R1-R022-R | G | PWA BOM | In Old BOM |
|  |  |  | HCB0430-220 | IND,HCB0430-220 | Delta | HCB0430-220 | G | PWA BOM | In Old BOM |
| 2 | PSRL2 | 1 | 63032PP00-088-G | IND,4.7uH@100KHz,+/-20%,5.5A,40mOhm,SHLD,G,SMD | COOPER BUSSMANN, INC. | HCM0703-4R7-R | G | PWA BOM | In New BOM |
|  |  |  | 63030PW00-034-G | Coil Ind,Shielded(SHLD),4.7uH@100KHz,+/-20%,5.5A,40mOhm,SMD,7.3*6.6*3.0,G | CYNTEC CO. LTD | PCMC063T-4R7MN | G | PWA BOM | In New BOM |
|  |  |  | 63031AD04-129-G | IND,4.7uH@100KHz,+/-20%,5.5A,40mOhm,SHLD,G,SMD | MAG.LAYERS, SCIENTIFIC-TECHNICS (KUNSHAN) CO., LTD. | SPS-06CZ-4R7M-V1 | G | PWA BOM | In New BOM |
|  | PSRL2 | 1 | 63032PP00-088-G | IND,4.7uH@100KHz,+/-20%,5.5A,40mOhm,SHLD,G,SMD | COOPER BUSSMANN, INC. | HCM0703-4R7-R | G | PWA BOM | In Old BOM |
|  |  |  | 63030PW00-034-G | Coil Ind,Shielded(SHLD),4.7uH@100KHz,+/-20%,5.5A,40mOhm,SMD,7.3*6.6*3.0,G | CYNTEC CO. LTD | PCMC063T-4R7MN | G | PWA BOM | In Old BOM |
|  |  |  | SPS-06CZ-4R7M-V1 | IND,SPS-06CZ-4R7M-V1 | MAG.LAYERS, SCIENTIFIC-TECHNICS (KUNSHAN) CO., LTD. | SPS-06CZ-4R7M-V1 | G | PWA BOM | In Old BOM |
| 3 | R1408,R1449 | 2 | 610107L00-017-G | RES,1 Ohm,+/-5%,1/10W,G,SMD0603 | KOA SPEER ELECTRONICS, INC. | RK73B1JTTD1R0J | G | PWA BOM | In New BOM |
|  |  |  | 610107L00-011-G | RES,1 Ohm,+/-5%,1/10W,G,SMD0603 | YAGEO CORPORATION COMPONENT | RC0603JR-071RL | G | PWA BOM | In New BOM |
|  |  |  | 610107L00-012-G | RES,1 Ohm,+/-5%,1/10W,G,SMD0603 | WALSIN TECHNOLOGY CORPORATION | WR06X1R0JTL | G | PWA BOM | In New BOM |
|  |  |  | 610107L00-044-G | RES,1 Ohm,+/-5%,1/10W,G,SMD0603 | TA-I TECHNOLOGY CO., LTD | RM06JTN1R0 | G | PWA BOM | In New BOM |
|  | R1408,R1449 | 2 | 610107L00-017-G | RES,1 Ohm,+/-5%,1/10W,G,SMD0603 | KOA SPEER ELECTRONICS, INC. | RK73B1JTTD1R0J | G | PWA BOM | In Old BOM |
|  |  |  | 610107L00-011-G | RES,1 Ohm,+/-5%,1/10W,G,SMD0603 | YAGEO CORPORATION COMPONENT | RC0603JR-071RL |  | PWA BOM | In Old BOM |
|  |  |  | 610107L00-012-G | RES,1 Ohm,+/-5%,1/10W,G,SMD0603 | WALSIN TECHNOLOGY CORPORATION | WR06X1R0JTL |  | PWA BOM | In Old BOM |
|  |  |  | 610107L00-044-G | RES,1 Ohm,+/-5%,1/10W,G,SMD0603 | TA-I TECHNOLOGY CO., LTD | RM06JTN1R0 |  | PWA BOM | In Old BOM |
| 4 | PCB | 1 | PCB | PCB | PCB | PCB | G | PWA BOM | In New BOM |
|  | PCB | 1 | 0101F2800-000-G | PCB,Zaius-Tri-mode BPX24 EVT-X00,OSP,Red,22L,21.122*3.470,G | GOLD CIRCUIT ELECTRONICS LTD. | 0101F2800-000-G | G | PWA BOM | In Old BOM |
| 5 | U248 | 1 | 220106A00-413-G | IC,PLD,10M08SCU169C8G,3.3V,116MHz,G,BGA-169,SMD | ALTERA CORPORATION | 10M08SCU169C8G | G | PWA BOM | In New BOM |
|  | U248 | 1 | 220107K00-413-G | IC,PLD,10M02SCU169C8G,116MHz,3.3V,G,UBGA-169,SMD | ALTERA CORPORATION | 10M02SCU169C8G | G | PWA BOM | In Old BOM |
| 6 | J_CPLD_JTAG | 1 | ZP91-0155C-1221 | CONN,Header,WTB,2X3,R/A,Bla,2.5mm,15u,G,SMD-6 | CENLINK | ZP91-0155C-1221 | G | PWA BOM | In New BOM |
|  | J_CPLD_JTAG | 1 | 3406B6F00-317-G | CONN,Header,WTB,2X3,R/A,Bla,2.5mm,15u,G,SMD-6 | MOLEX INCORPORATED | 15-91-2065 | G | PWA BOM | In Old BOM |
| ##### Change Revision |  |  |  |  |  |  |  |  |  |
| Sheet | REV OF BOM | CUSTOMER | CUSTOMER P/N | PWA PN | PWA DESCRIPTION | PWA REV | DATE | Remark |  |
| PWA BOM |  | Customer |  |  |  |  |  | In New BOM |  |
| PWA BOM | X03 | Customer |  |  |  |  | 6/5/17 | In Old BOM |  |
| OOOOOOOOOOOOOOOOOOOOOOOOOOOOOOOOOOOOOOOOOOOOOOOOOOOOOOOOOOOOOOOOOOOOOOOOOOOOOOOOOOOOOOOOOO | OOOOOOOOOOOOOOOOOOOOOOOOOOOOOOOOOOOOOOOOOOOOOOOOOOOOOOOOOOOOOOOOOOOOOOOOOOOOOOOOOOOOOOOOOO | OOOOOOOOOOOOOOOOOOOOOOOOOOOOOOOOOOOOOOOOOOOOOOOOOOOOOOOOOOOOOOOOOOOOOOOOOOOOOOOOOOOOOOOOOO | OOOOOOOOOOOOOOOOOOOOOOOOOOOOOOOOOOOOOOOOOOOOOOOOOOOOOOOOOOOOOOOOOOOOOOOOOOOOOOOOOOOOOOOOOO | OOOOOOOOOOOOOOOOOOOOOOOOOOOOOOOOOOOOOOOOOOOOOOOOOOOOOOOOOOOOOOOOOOOOOOOOOOOOOOOOOOOOOOOOOO | OOOOOOOOOOOOOOOOOOOOOOOOOOOOOOOOOOOOOOOOOOOOOOOOOOOOOOOOOOOOOOOOOOOOOOOOOOOOOOOOOOOOOOOOOO | OOOOOOOOOOOOOOOOOOOOOOOOOOOOOOOOOOOOOOOOOOOOOOOOOOOOOOOOOOOOOOOOOOOOOOOOOOOOOOOOOOOOOOOOOO | OOOOOOOOOOOOOOOOOOOOOOOOOOOOOOOOOOOOOOOOOOOOOOOOOOOOOOOOOOOOOOOOOOOOOOOOOOOOOOOOOOOOOOOOOO | OOOOOOOOOOOOOOOOOOOOOOOOOOOOOOOOOOOOOOOOOOOOOOOOOOOOOOOOOOOOOOOOOOOOOOOOOOOOOOOOOOOOOOOOOO | OOOOOOOOOOOOOOOOOOOOOOOOOOOOOOOOOOOOOOOOOOOOOOOOOOOOOOOOOOOOOOOOOOOOOOOOOOOOOOOOOOOOOOOOOO |
| Second Source Change |  |  |  |  |  |  |  |  |  |
| Item | Location | Change Type | Foxconn P/N | Part Description | Manufacturer Full Name | Manufacturer P/N | RoHS | Sheet |  |
| 1 | PSTL2,PFTL2,PETL2 |  | 630341400-088-G | IND,22nH@1MHz,+/-20%,19A,368uOhm,SHLD,G,SMD | COOPER BUSSMANN, INC. | FP0404R1-R022-R | G | PWA BOM |  |
|  |  | ADD | 630362G00-065-G | 22nH@100KHz,+/-20%,19A,0.32mOhm,SHLD,G,SMD | Delta | HCB0430-220 | G | PWA BOM |  |
|  |  | Delete | HCB0430-220 | IND,HCB0430-220 | Delta | HCB0430-220 | G | PWA BOM |  |
| 2 | PSRL2 |  | 63032PP00-088-G | IND,4.7uH@100KHz,+/-20%,5.5A,40mOhm,SHLD,G,SMD | COOPER BUSSMANN, INC. | HCM0703-4R7-R | G | PWA BOM |  |
|  |  | NO | 63030PW00-034-G | Coil Ind,Shielded(SHLD),4.7uH@100KHz,+/-20%,5.5A,40mOhm,SMD,7.3*6.6*3.0,G | CYNTEC CO. LTD | PCMC063T-4R7MN | G | PWA BOM |  |
|  |  | ADD | 63031AD04-129-G | IND,4.7uH@100KHz,+/-20%,5.5A,40mOhm,SHLD,G,SMD | MAG.LAYERS, SCIENTIFIC-TECHNICS (KUNSHAN) CO., LTD. | SPS-06CZ-4R7M-V1 | G | PWA BOM |  |
|  |  | Delete | SPS-06CZ-4R7M-V1 | IND,SPS-06CZ-4R7M-V1 | MAG.LAYERS, SCIENTIFIC-TECHNICS (KUNSHAN) CO., LTD. | SPS-06CZ-4R7M-V1 | G | PWA BOM |  |
| OOOOOOOOOOOOOOOOOOOOOOOOOOOOOOOOOOOOOOOOOOOOOOOOOOOOOOOOOOOOOOOOOOOOOOOOOOOOOOOOOOOOOOOOOO | OOOOOOOOOOOOOOOOOOOOOOOOOOOOOOOOOOOOOOOOOOOOOOOOOOOOOOOOOOOOOOOOOOOOOOOOOOOOOOOOOOOOOOOOOO | OOOOOOOOOOOOOOOOOOOOOOOOOOOOOOOOOOOOOOOOOOOOOOOOOOOOOOOOOOOOOOOOOOOOOOOOOOOOOOOOOOOOOOOOOO | OOOOOOOOOOOOOOOOOOOOOOOOOOOOOOOOOOOOOOOOOOOOOOOOOOOOOOOOOOOOOOOOOOOOOOOOOOOOOOOOOOOOOOOOOO | OOOOOOOOOOOOOOOOOOOOOOOOOOOOOOOOOOOOOOOOOOOOOOOOOOOOOOOOOOOOOOOOOOOOOOOOOOOOOOOOOOOOOOOOOO | OOOOOOOOOOOOOOOOOOOOOOOOOOOOOOOOOOOOOOOOOOOOOOOOOOOOOOOOOOOOOOOOOOOOOOOOOOOOOOOOOOOOOOOOOO | OOOOOOOOOOOOOOOOOOOOOOOOOOOOOOOOOOOOOOOOOOOOOOOOOOOOOOOOOOOOOOOOOOOOOOOOOOOOOOOOOOOOOOOOOO | OOOOOOOOOOOOOOOOOOOOOOOOOOOOOOOOOOOOOOOOOOOOOOOOOOOOOOOOOOOOOOOOOOOOOOOOOOOOOOOOOOOOOOOOOO | OOOOOOOOOOOOOOOOOOOOOOOOOOOOOOOOOOOOOOOOOOOOOOOOOOOOOOOOOOOOOOOOOOOOOOOOOOOOOOOOOOOOOOOOOO | OOOOOOOOOOOOOOOOOOOOOOOOOOOOOOOOOOOOOOOOOOOOOOOOOOOOOOOOOOOOOOOOOOOOOOOOOOOOOOOOOOOOOOOOOO |
| Master Materials Change |  |  |  |  |  |  |  |  |  |
| Item | Foxconn P/N | Orig._Usage | New_Usage | Part Description | Manufacturer Full Name | Manufacturer P/N | RoHS | Location | Sheet |
| 1 | PCB | 0 | 1 | PCB | PCB | PCB | G | (+)PCB | PWA BOM |
| 2 | 220106A00-413-G | 0 | 1 | IC,PLD,10M08SCU169C8G,3.3V,116MHz,G,BGA-169,SMD | ALTERA CORPORATION | 10M08SCU169C8G | G | (+)U248 | PWA BOM |
| 3 | ZP91-0155C-1221 | 0 | 1 | CONN,Header,WTB,2X3,R/A,Bla,2.5mm,15u,G,SMD-6 | CENLINK | ZP91-0155C-1221 | G | (+)J_CPLD_JTAG | PWA BOM |
| 4 | 0101F2800-000-G | 1 | 0 | PCB,Zaius-Tri-mode BPX24 EVT-X00,OSP,Red,22L,21.122*3.470,G | GOLD CIRCUIT ELECTRONICS LTD. | 0101F2800-000-G | G | (-)PCB | PWA BOM |
| 5 | 220107K00-413-G | 1 | 0 | IC,PLD,10M02SCU169C8G,116MHz,3.3V,G,UBGA-169,SMD | ALTERA CORPORATION | 10M02SCU169C8G | G | (-)U248 | PWA BOM |
| 6 | 3406B6F00-317-G | 1 | 0 | CONN,Header,WTB,2X3,R/A,Bla,2.5mm,15u,G,SMD-6 | MOLEX INCORPORATED | 15-91-2065 | G | (-)J_CPLD_JTAG | PWA BOM |
| OOOOOOOOOOOOOOOOOOOOOOOOOOOOOOOOOOOOOOOOOOOOOOOOOOOOOOOOOOOOOOOOOOOOOOOOOOOOOOOOOOOOOOOOOO | OOOOOOOOOOOOOOOOOOOOOOOOOOOOOOOOOOOOOOOOOOOOOOOOOOOOOOOOOOOOOOOOOOOOOOOOOOOOOOOOOOOOOOOOOO | OOOOOOOOOOOOOOOOOOOOOOOOOOOOOOOOOOOOOOOOOOOOOOOOOOOOOOOOOOOOOOOOOOOOOOOOOOOOOOOOOOOOOOOOOO | OOOOOOOOOOOOOOOOOOOOOOOOOOOOOOOOOOOOOOOOOOOOOOOOOOOOOOOOOOOOOOOOOOOOOOOOOOOOOOOOOOOOOOOOOO | OOOOOOOOOOOOOOOOOOOOOOOOOOOOOOOOOOOOOOOOOOOOOOOOOOOOOOOOOOOOOOOOOOOOOOOOOOOOOOOOOOOOOOOOOO | OOOOOOOOOOOOOOOOOOOOOOOOOOOOOOOOOOOOOOOOOOOOOOOOOOOOOOOOOOOOOOOOOOOOOOOOOOOOOOOOOOOOOOOOOO | OOOOOOOOOOOOOOOOOOOOOOOOOOOOOOOOOOOOOOOOOOOOOOOOOOOOOOOOOOOOOOOOOOOOOOOOOOOOOOOOOOOOOOOOOO | OOOOOOOOOOOOOOOOOOOOOOOOOOOOOOOOOOOOOOOOOOOOOOOOOOOOOOOOOOOOOOOOOOOOOOOOOOOOOOOOOOOOOOOOOO | OOOOOOOOOOOOOOOOOOOOOOOOOOOOOOOOOOOOOOOOOOOOOOOOOOOOOOOOOOOOOOOOOOOOOOOOOOOOOOOOOOOOOOOOOO | OOOOOOOOOOOOOOOOOOOOOOOOOOOOOOOOOOOOOOOOOOOOOOOOOOOOOOOOOOOOOOOOOOOOOOOOOOOOOOOOOOOOOOOOOO |
| TLA Parts Change |  |  |  |  |  |  |  |  |  |
| Item | Foxconn P/N | Qty | Part Description | Manufacturer Full Name | Manufacturer P/N | RoHS | Location | Remark | BOM |
| BOM Change List Date:Thu Aug 31 16:50:13 GMT+08:00 2017 |  |  |  |  |  |  |  |  |  |
| New BOM file : E:\barreleye g2\0830\EXPANDER BPX24\Barreleye-G2_Tri-mode BPX24-DVT-X01-BOM-X04-20170831.xls |  |  |  |  |  |  |  |  |  |
| Old BOM file : E:\barreleye g2\0830\EXPANDER BPX24\BPX24 0825.xls |  |  |  |  |  |  |  |  |  |
| ##### Add Parts |  |  |  |  |  |  |  |  |  |
| Item | Location | Qty | Foxconn P/N | Part Description | Manufacturer Full Name | Manufacturer P/N | RoHS | Sheet |  |
| 1 | C2271 | 1 | 620101T02-015-G | CAP,100nF,+/-10%,X7R,16V,G,SMD0402 | MURATA ELEC. NORTH AMERICA | GRM155R71C104K | G | PWA BOM |  |
|  |  |  | 620101T00-012-G | CAP,100nF,+/-10%,X7R,16V,G,SMD0402 | WALSIN TECHNOLOGY CORPORATION | 0402B104K160CT | G | PWA BOM |  |
|  |  |  | 620101T00-026-G | CAP,100nF,+/-10%,X7R,16V,G,SMD0402 | SAMSUNG SEMICONDUCTOR | CL05B104KO5NNNC | G | PWA BOM |  |
|  |  |  | 620101T00-015-G | CAP,100nF,+/-10%,X7R,16V,G,SMD0402 | MURATA ELEC. NORTH AMERICA | GRM155R71C104KA88D | G | PWA BOM |  |
| 2 | R2152,R2153,R2154,R2155 | 4 | 610107A00-017-G | RES,0 Ohm,+/-5%,1/16W,G,SMD0402 | KOA SPEER ELECTRONICS, INC. | RK73Z1ETTP | G | PWA BOM |  |
|  |  |  | 610107A00-012-G | RES,0 Ohm,+/-5%,1/16W,G,SMD0402 | WALSIN TECHNOLOGY CORPORATION | WR04X000PTL | G | PWA BOM |  |
|  |  |  | 610107A00-011-G | RES,0 Ohm,+/-5%,1/16W,G,SMD0402 | YAGEO CORPORATION COMPONENT | RC0402JR-070RL | G | PWA BOM |  |
|  |  |  | 610107A00-044-G | RES,0 Ohm,+/-5%,1/16W,G,SMD0402 | TA-I TECHNOLOGY CO., LTD | RM04JTN0 | G | PWA BOM |  |
|  |  |  | 610107A00-024-G | RES,0 Ohm,+/-5%,1/16W,G,SMD0402 | PANASONIC INDUSTRIAL CO.,LTD. | ERJ2GE0R00X | G | PWA BOM |  |
|  |  |  | 610107A00-029-G | RES,0 Ohm,+/-5%,1/16W,G,SMD0402 | VISHAY ENTER TECHNO LOGY.INC | CRCW04020000Z0ED | G | PWA BOM |  |
| ##### Remove Parts |  |  |  |  |  |  |  |  |  |
| Item | Location | Qty | Foxconn P/N | Part Description | Manufacturer Full Name | Manufacturer P/N | RoHS | Sheet |  |
| 1 | R229,R230 | 2 | 61010LA00-017-G | RES,4.7KOhm,+/-1%,1/16W,G,SMD0402 | KOA SPEER ELECTRONICS, INC. | RK73H1ETTP4701F | G | PWA BOM |  |
|  |  |  | 61010LA00-012-G | RES,4.7KOhm,+/-1%,1/16W,G,SMD0402 | WALSIN TECHNOLOGY CORPORATION | WR04X4701FTL | G | PWA BOM |  |
|  |  |  | 61010LA00-011-G | RES,4.7KOhm,+/-1%,1/16W,G,SMD0402 | YAGEO CORPORATION COMPONENT | RC0402FR-074K7L | G | PWA BOM |  |
|  |  |  | 61010LA00-044-G | RES,4.7KOhm,+/-1%,1/16W,G,SMD0402 | TA-I TECHNOLOGY CO., LTD | RM04FTN4701 | G | PWA BOM |  |
| ##### Change Parts |  |  |  |  |  |  |  |  |  |
| Item | Location | Qty | Foxconn P/N | Part Description | Manufacturer Full Name | Manufacturer P/N | RoHS | Sheet | Remark |
| 1 | R251,R252 | 2 | 610118100-017-G | RES,1.4KOhm,+/-1%,1/16W,G,SMD0402 | KOA SPEER ELECTRONICS, INC. | RK73H1ETTP1401F | G | PWA BOM | In New BOM |
|  | R251,R252 | 2 | 61010LA00-017-G | RES,4.7KOhm,+/-1%,1/16W,G,SMD0402 | KOA SPEER ELECTRONICS, INC. | RK73H1ETTP4701F | G | PWA BOM | In Old BOM |
|  |  |  | 61010LA00-012-G | RES,4.7KOhm,+/-1%,1/16W,G,SMD0402 | WALSIN TECHNOLOGY CORPORATION | WR04X4701FTL | G | PWA BOM | In Old BOM |
|  |  |  | 61010LA00-011-G | RES,4.7KOhm,+/-1%,1/16W,G,SMD0402 | YAGEO CORPORATION COMPONENT | RC0402FR-074K7L | G | PWA BOM | In Old BOM |
|  |  |  | 61010LA00-044-G | RES,4.7KOhm,+/-1%,1/16W,G,SMD0402 | TA-I TECHNOLOGY CO., LTD | RM04FTN4701 | G | PWA BOM | In Old BOM |
| 2 | R1313,R1785,R1787,R1788,R1791,R1793,R1795,R1796,R1799,R1800,R1803,R1804,R1807,R1808,R1811,R1812,R1815,R1816,R1819,R1820,R1823,R1824,R1827,R1828 | 24 | 61011MV00-017-G | RES,510 Ohm,+/-1%,1/16W,G,SMD0402 | KOA SPEER ELECTRONICS, INC. | RK73H1ETTP5100F | G | PWA BOM | In New BOM |
|  | R1313,R1785,R1787,R1788,R1791,R1793,R1795,R1796,R1799,R1800,R1803,R1804,R1807,R1808,R1811,R1812,R1815,R1816,R1819,R1820,R1823,R1824,R1827,R1828 | 24 | 61100AH00-017-G | RES,10KOhm,+/-0.5%,1/16W,G,SMD0402 | KOA SPEER ELECTRONICS, INC. | RN731ETTP1002D25 | G | PWA BOM | In Old BOM |
|  |  |  | 61100AH00-012-G | RES,10KOhm,+/-0.5%,1/16W,G,SMD0402 | WALSIN TECHNOLOGY CORPORATION | WF04U1002DTL | G | PWA BOM | In Old BOM |
|  |  |  | 61100AH00-011-G | RES,10KOhm,+/-0.5%,1/16W,G,SMD0402 | YAGEO CORPORATION COMPONENT | RT0402DRE0710KL | G | PWA BOM | In Old BOM |
|  |  |  | 61100AH00-044-G | RES,10KOhm,+/-0.5%,1/16W,G,SMD0402 | TA-I TECHNOLOGY CO., LTD | RB04DTP1002 | G | PWA BOM | In Old BOM |
| 3 | R1314,R1786,R1789,R1790,R1792,R1794,R1797,R1798,R1801,R1802,R1805,R1806,R1809,R1810,R1813,R1814,R1817,R1818,R1821,R1822,R1825,R1826,R1829,R1830 | 24 | 61011FA00-017-G | RES,1.02KOhm,+/-1%,1/16W,G,SMD0402 | KOA SPEER ELECTRONICS, INC. | RK73H1ETTP1021F | G | PWA BOM | In New BOM |
|  | R1314,R1786,R1789,R1790,R1792,R1794,R1797,R1798,R1801,R1802,R1805,R1806,R1809,R1810,R1813,R1814,R1817,R1818,R1821,R1822,R1825,R1826,R1829,R1830 | 24 | 61010FG00-017-G | RES,20KOhm,+/-5%,1/16W,G,SMD0402 | KOA SPEER ELECTRONICS, INC. | RK73B1ETTP203J | G | PWA BOM | In Old BOM |
|  |  |  | 61010FG00-012-G | RES,20KOhm,+/-5%,1/16W,G,SMD0402 | WALSIN TECHNOLOGY CORPORATION | WR04X203JTL | G | PWA BOM | In Old BOM |
|  |  |  | 61010FG00-011-G | RES,20KOhm,+/-5%,1/16W,G,SMD0402 | YAGEO CORPORATION COMPONENT | RC0402JR-0720KL | G | PWA BOM | In Old BOM |
| 4 | J_CPLD_JTAG | 1 | 3406B6F00-317-G | CONN,Header,WTB,2X3,R/A,Bla,2.5mm,15u,G,SMD-6 | MOLEX INCORPORATED | 15-91-2065 | G | PWA BOM | In New BOM |
|  | J_CPLD_JTAG | 1 | ZP91-0155C-1221 | CONN,Header,WTB,2X3,R/A,Bla,2.5mm,15u,G,SMD-6 | CENLINK | ZP91-0155C-1221 | G | PWA BOM | In Old BOM |
| ##### Change Revision |  |  |  |  |  |  |  |  |  |
| Sheet | REV OF BOM | CUSTOMER | CUSTOMER P/N | PWA PN | PWA DESCRIPTION | PWA REV | DATE | Remark |  |
| OOOOOOOOOOOOOOOOOOOOOOOOOOOOOOOOOOOOOOOOOOOOOOOOOOOOOOOOOOOOOOOOOOOOOOOOOOOOOOOOOOOOOOOOOO | OOOOOOOOOOOOOOOOOOOOOOOOOOOOOOOOOOOOOOOOOOOOOOOOOOOOOOOOOOOOOOOOOOOOOOOOOOOOOOOOOOOOOOOOOO | OOOOOOOOOOOOOOOOOOOOOOOOOOOOOOOOOOOOOOOOOOOOOOOOOOOOOOOOOOOOOOOOOOOOOOOOOOOOOOOOOOOOOOOOOO | OOOOOOOOOOOOOOOOOOOOOOOOOOOOOOOOOOOOOOOOOOOOOOOOOOOOOOOOOOOOOOOOOOOOOOOOOOOOOOOOOOOOOOOOOO | OOOOOOOOOOOOOOOOOOOOOOOOOOOOOOOOOOOOOOOOOOOOOOOOOOOOOOOOOOOOOOOOOOOOOOOOOOOOOOOOOOOOOOOOOO | OOOOOOOOOOOOOOOOOOOOOOOOOOOOOOOOOOOOOOOOOOOOOOOOOOOOOOOOOOOOOOOOOOOOOOOOOOOOOOOOOOOOOOOOOO | OOOOOOOOOOOOOOOOOOOOOOOOOOOOOOOOOOOOOOOOOOOOOOOOOOOOOOOOOOOOOOOOOOOOOOOOOOOOOOOOOOOOOOOOOO | OOOOOOOOOOOOOOOOOOOOOOOOOOOOOOOOOOOOOOOOOOOOOOOOOOOOOOOOOOOOOOOOOOOOOOOOOOOOOOOOOOOOOOOOOO | OOOOOOOOOOOOOOOOOOOOOOOOOOOOOOOOOOOOOOOOOOOOOOOOOOOOOOOOOOOOOOOOOOOOOOOOOOOOOOOOOOOOOOOOOO | OOOOOOOOOOOOOOOOOOOOOOOOOOOOOOOOOOOOOOOOOOOOOOOOOOOOOOOOOOOOOOOOOOOOOOOOOOOOOOOOOOOOOOOOOO |
| Second Source Change |  |  |  |  |  |  |  |  |  |
| Item | Location | Change Type | Foxconn P/N | Part Description | Manufacturer Full Name | Manufacturer P/N | RoHS | Sheet |  |
| OOOOOOOOOOOOOOOOOOOOOOOOOOOOOOOOOOOOOOOOOOOOOOOOOOOOOOOOOOOOOOOOOOOOOOOOOOOOOOOOOOOOOOOOOO | OOOOOOOOOOOOOOOOOOOOOOOOOOOOOOOOOOOOOOOOOOOOOOOOOOOOOOOOOOOOOOOOOOOOOOOOOOOOOOOOOOOOOOOOOO | OOOOOOOOOOOOOOOOOOOOOOOOOOOOOOOOOOOOOOOOOOOOOOOOOOOOOOOOOOOOOOOOOOOOOOOOOOOOOOOOOOOOOOOOOO | OOOOOOOOOOOOOOOOOOOOOOOOOOOOOOOOOOOOOOOOOOOOOOOOOOOOOOOOOOOOOOOOOOOOOOOOOOOOOOOOOOOOOOOOOO | OOOOOOOOOOOOOOOOOOOOOOOOOOOOOOOOOOOOOOOOOOOOOOOOOOOOOOOOOOOOOOOOOOOOOOOOOOOOOOOOOOOOOOOOOO | OOOOOOOOOOOOOOOOOOOOOOOOOOOOOOOOOOOOOOOOOOOOOOOOOOOOOOOOOOOOOOOOOOOOOOOOOOOOOOOOOOOOOOOOOO | OOOOOOOOOOOOOOOOOOOOOOOOOOOOOOOOOOOOOOOOOOOOOOOOOOOOOOOOOOOOOOOOOOOOOOOOOOOOOOOOOOOOOOOOOO | OOOOOOOOOOOOOOOOOOOOOOOOOOOOOOOOOOOOOOOOOOOOOOOOOOOOOOOOOOOOOOOOOOOOOOOOOOOOOOOOOOOOOOOOOO | OOOOOOOOOOOOOOOOOOOOOOOOOOOOOOOOOOOOOOOOOOOOOOOOOOOOOOOOOOOOOOOOOOOOOOOOOOOOOOOOOOOOOOOOOO | OOOOOOOOOOOOOOOOOOOOOOOOOOOOOOOOOOOOOOOOOOOOOOOOOOOOOOOOOOOOOOOOOOOOOOOOOOOOOOOOOOOOOOOOOO |
| Master Materials Change |  |  |  |  |  |  |  |  |  |
| Item | Foxconn P/N | Orig._Usage | New_Usage | Part Description | Manufacturer Full Name | Manufacturer P/N | RoHS | Location | Sheet |
| 1 | 620101T02-015-G | 143 | 144 | CAP,100nF,+/-10%,X7R,16V,G,SMD0402 | MURATA ELEC. NORTH AMERICA | GRM155R71C104K | G | (+)C2271 | PWA BOM |
|  | 620101T00-012-G |  |  | CAP,100nF,+/-10%,X7R,16V,G,SMD0402 | WALSIN TECHNOLOGY CORPORATION | 0402B104K160CT |  |  | PWA BOM |
|  | 620101T00-026-G |  |  | CAP,100nF,+/-10%,X7R,16V,G,SMD0402 | SAMSUNG SEMICONDUCTOR | CL05B104KO5NNNC |  |  | PWA BOM |
|  | 620101T00-015-G |  |  | CAP,100nF,+/-10%,X7R,16V,G,SMD0402 | MURATA ELEC. NORTH AMERICA | GRM155R71C104KA88D |  |  | PWA BOM |
| 2 | 61010LA00-017-G | 49 | 45 | RES,4.7KOhm,+/-1%,1/16W,G,SMD0402 | KOA SPEER ELECTRONICS, INC. | RK73H1ETTP4701F | G | (-)R229,R230,R251,R252 | PWA BOM |
|  | 61010LA00-012-G |  |  | RES,4.7KOhm,+/-1%,1/16W,G,SMD0402 | WALSIN TECHNOLOGY CORPORATION | WR04X4701FTL |  |  | PWA BOM |
|  | 61010LA00-011-G |  |  | RES,4.7KOhm,+/-1%,1/16W,G,SMD0402 | YAGEO CORPORATION COMPONENT | RC0402FR-074K7L |  |  | PWA BOM |
|  | 61010LA00-044-G |  |  | RES,4.7KOhm,+/-1%,1/16W,G,SMD0402 | TA-I TECHNOLOGY CO., LTD | RM04FTN4701 |  |  | PWA BOM |
| 3 | 610107A00-017-G | 121 | 125 | RES,0 Ohm,+/-5%,1/16W,G,SMD0402 | KOA SPEER ELECTRONICS, INC. | RK73Z1ETTP | G | (+)R2152,R2153,R2154,R2155 | PWA BOM |
|  | 610107A00-012-G |  |  | RES,0 Ohm,+/-5%,1/16W,G,SMD0402 | WALSIN TECHNOLOGY CORPORATION | WR04X000PTL |  |  | PWA BOM |
|  | 610107A00-011-G |  |  | RES,0 Ohm,+/-5%,1/16W,G,SMD0402 | YAGEO CORPORATION COMPONENT | RC0402JR-070RL |  |  | PWA BOM |
|  | 610107A00-044-G |  |  | RES,0 Ohm,+/-5%,1/16W,G,SMD0402 | TA-I TECHNOLOGY CO., LTD | RM04JTN0 |  |  | PWA BOM |
|  | 610107A00-024-G |  |  | RES,0 Ohm,+/-5%,1/16W,G,SMD0402 | PANASONIC INDUSTRIAL CO.,LTD. | ERJ2GE0R00X |  |  | PWA BOM |
|  | 610107A00-029-G |  |  | RES,0 Ohm,+/-5%,1/16W,G,SMD0402 | VISHAY ENTER TECHNO LOGY.INC | CRCW04020000Z0ED |  |  | PWA BOM |
| 4 | 610118100-017-G | 0 | 2 | RES,1.4KOhm,+/-1%,1/16W,G,SMD0402 | KOA SPEER ELECTRONICS, INC. | RK73H1ETTP1401F | G | (+)R251,R252 | PWA BOM |
| 5 | 61011MV00-017-G | 0 | 24 | RES,510 Ohm,+/-1%,1/16W,G,SMD0402 | KOA SPEER ELECTRONICS, INC. | RK73H1ETTP5100F | G | (+)R1313,R1785,R1787,R1788,R1791,R1793,R1795,R1796,R1799,R1800,R1803,R1804,R1807,R1808,R1811,R1812,R1815,R1816,R1819,R1820,R1823,R1824,R1827,R1828 | PWA BOM |
| 6 | 61011FA00-017-G | 0 | 24 | RES,1.02KOhm,+/-1%,1/16W,G,SMD0402 | KOA SPEER ELECTRONICS, INC. | RK73H1ETTP1021F | G | (+)R1314,R1786,R1789,R1790,R1792,R1794,R1797,R1798,R1801,R1802,R1805,R1806,R1809,R1810,R1813,R1814,R1817,R1818,R1821,R1822,R1825,R1826,R1829,R1830 | PWA BOM |
| 7 | 61100AH00-017-G | 36 | 12 | RES,10KOhm,+/-0.5%,1/16W,G,SMD0402 | KOA SPEER ELECTRONICS, INC. | RN731ETTP1002D25 | G | (-)R1313,R1785,R1787,R1788,R1791,R1793,R1795,R1796,R1799,R1800,R1803,R1804,R1807,R1808,R1811,R1812,R1815,R1816,R1819,R1820,R1823,R1824,R1827,R1828 | PWA BOM |
|  | 61100AH00-012-G |  |  | RES,10KOhm,+/-0.5%,1/16W,G,SMD0402 | WALSIN TECHNOLOGY CORPORATION | WF04U1002DTL |  |  | PWA BOM |
|  | 61100AH00-011-G |  |  | RES,10KOhm,+/-0.5%,1/16W,G,SMD0402 | YAGEO CORPORATION COMPONENT | RT0402DRE0710KL |  |  | PWA BOM |
|  | 61100AH00-044-G |  |  | RES,10KOhm,+/-0.5%,1/16W,G,SMD0402 | TA-I TECHNOLOGY CO., LTD | RB04DTP1002 |  |  | PWA BOM |
| 8 | 3406B6F00-317-G | 0 | 1 | CONN,Header,WTB,2X3,R/A,Bla,2.5mm,15u,G,SMD-6 | MOLEX INCORPORATED | 15-91-2065 | G | (+)J_CPLD_JTAG | PWA BOM |
| 9 | 61010FG00-017-G | 24 | 0 | RES,20KOhm,+/-5%,1/16W,G,SMD0402 | KOA SPEER ELECTRONICS, INC. | RK73B1ETTP203J | G | (-)R1314,R1786,R1789,R1790,R1792,R1794,R1797,R1798,R1801,R1802,R1805,R1806,R1809,R1810,R1813,R1814,R1817,R1818,R1821,R1822,R1825,R1826,R1829,R1830 | PWA BOM |
|  | 61010FG00-012-G |  |  | RES,20KOhm,+/-5%,1/16W,G,SMD0402 | WALSIN TECHNOLOGY CORPORATION | WR04X203JTL |  |  | PWA BOM |
|  | 61010FG00-011-G |  |  | RES,20KOhm,+/-5%,1/16W,G,SMD0402 | YAGEO CORPORATION COMPONENT | RC0402JR-0720KL |  |  | PWA BOM |
| 10 | ZP91-0155C-1221 | 1 | 0 | CONN,Header,WTB,2X3,R/A,Bla,2.5mm,15u,G,SMD-6 | CENLINK | ZP91-0155C-1221 | G | (-)J_CPLD_JTAG | PWA BOM |
| OOOOOOOOOOOOOOOOOOOOOOOOOOOOOOOOOOOOOOOOOOOOOOOOOOOOOOOOOOOOOOOOOOOOOOOOOOOOOOOOOOOOOOOOOO | OOOOOOOOOOOOOOOOOOOOOOOOOOOOOOOOOOOOOOOOOOOOOOOOOOOOOOOOOOOOOOOOOOOOOOOOOOOOOOOOOOOOOOOOOO | OOOOOOOOOOOOOOOOOOOOOOOOOOOOOOOOOOOOOOOOOOOOOOOOOOOOOOOOOOOOOOOOOOOOOOOOOOOOOOOOOOOOOOOOOO | OOOOOOOOOOOOOOOOOOOOOOOOOOOOOOOOOOOOOOOOOOOOOOOOOOOOOOOOOOOOOOOOOOOOOOOOOOOOOOOOOOOOOOOOOO | OOOOOOOOOOOOOOOOOOOOOOOOOOOOOOOOOOOOOOOOOOOOOOOOOOOOOOOOOOOOOOOOOOOOOOOOOOOOOOOOOOOOOOOOOO | OOOOOOOOOOOOOOOOOOOOOOOOOOOOOOOOOOOOOOOOOOOOOOOOOOOOOOOOOOOOOOOOOOOOOOOOOOOOOOOOOOOOOOOOOO | OOOOOOOOOOOOOOOOOOOOOOOOOOOOOOOOOOOOOOOOOOOOOOOOOOOOOOOOOOOOOOOOOOOOOOOOOOOOOOOOOOOOOOOOOO | OOOOOOOOOOOOOOOOOOOOOOOOOOOOOOOOOOOOOOOOOOOOOOOOOOOOOOOOOOOOOOOOOOOOOOOOOOOOOOOOOOOOOOOOOO | OOOOOOOOOOOOOOOOOOOOOOOOOOOOOOOOOOOOOOOOOOOOOOOOOOOOOOOOOOOOOOOOOOOOOOOOOOOOOOOOOOOOOOOOOO |  |
| TLA Parts Change |  |  |  |  |  |  |  |  |  |
| Item | Foxconn P/N | Qty | Part Description | Manufacturer Full Name | Manufacturer P/N | RoHS | Location | Remark |  |
| BOM Change List Date:Fri Sep 08 17:16:06 GMT+08:00 2017 |  |  |  |  |  |  |  |  |  |
| New BOM file : E:\barreleye g2\0905\BPX24 EXPANDER\BPX24 0906 .xls |  |  |  |  |  |  |  |  |  |
| Old BOM file : E:\barreleye g2\0905\BPX24 EXPANDER\BPX24 0831 .xls |  |  |  |  |  |  |  |  |  |
| ##### Add Parts |  |  |  |  |  |  |  |  |  |
| Item | Location | Qty | Foxconn P/N | Part Description | Manufacturer Full Name | Manufacturer P/N | RoHS | Sheet |  |
| ##### Remove Parts |  |  |  |  |  |  |  |  |  |
| Item | Location | Qty | Foxconn P/N | Part Description | Manufacturer Full Name | Manufacturer P/N | RoHS | Sheet |  |
| ##### Change Parts |  |  |  |  |  |  |  |  |  |
| Item | Location | Qty | Foxconn P/N | Part Description | Manufacturer Full Name | Manufacturer P/N | RoHS | Sheet | Remark |
| 1 | PSTR5,PFTR5,PETR5 | 3 | 61100QD00-017-G | RES,787 Ohm,+/-0.1%,1/16W,G,SMD0402 | KOA SPEER ELECTRONICS, INC. | RN731ETTP7870B25 | G | PWA BOM | In New BOM |
|  |  |  | 61100QD00-011-G | RES,787 Ohm,+/-0.1%,1/16W,G,SMD0402 | YAGEO CORPORATION COMPONENT | RT0402BRD07787RL | G | PWA BOM | In New BOM |
|  |  |  | 61100QD00-044-G | RES,787 Ohm,+/-0.1%,1/16W,G,SMD0402 | TA-I TECHNOLOGY CO., LTD | RB04BTP7870 | G | PWA BOM | In New BOM |
|  |  |  | 61100QD00-012-G | RES,787 Ohm,+/-0.1%,1/16W,G,SMD0402 | WALSIN TECHNOLOGY CORPORATION | WF04U7870BTL | G | PWA BOM | In New BOM |
|  | PSTR5,PFTR5,PETR5 | 3 | 61100QD00-017-G | RES,787 Ohm,+/-0.1%,1/16W,G,SMD0402 | KOA SPEER ELECTRONICS, INC. | RN731ETTP7870B25 | G | PWA BOM | In Old BOM |
|  |  |  | 61100QD00-012-G | RES,787 Ohm,+/-0.1%,1/16W,G,SMD0402 | WALSIN TECHNOLOGY CORPORATION | WF04U7870BTL | G | PWA BOM | In Old BOM |
|  |  |  | 61100QD00-011-G | RES,787 Ohm,+/-0.1%,1/16W,G,SMD0402 | YAGEO CORPORATION COMPONENT | RT0402BRD07787RL | G | PWA BOM | In Old BOM |
| 2 | PSTR6,PFTR6,PETR6 | 3 | 61100SU00-017-G | RES,105 Ohm,+/-0.1%,1/16W,G,SMD0402 | KOA SPEER ELECTRONICS, INC. | RN731ETTP1050B25 | G | PWA BOM | In New BOM |
|  |  |  | 61100SU00-011-G | RES,105 Ohm,+/-0.1%,1/16W,G,SMD0402 | YAGEO CORPORATION COMPONENT | RT0402BRD07105RL | G | PWA BOM | In New BOM |
|  |  |  | 61100SU00-044-G | RES,105 Ohm,+/-0.1%,1/16W,G,SMD0402 | TA-I TECHNOLOGY CO., LTD | RB04BTP1050 | G | PWA BOM | In New BOM |
|  |  |  | 61100SU00-012-G | RES,105 Ohm,+/-0.1%,1/16W,G,SMD0402 | WALSIN TECHNOLOGY CORPORATION | WF04U1050BTL | G | PWA BOM | In New BOM |
|  | PSTR6,PFTR6,PETR6 | 3 | 61100SU00-017-G | RES,105 Ohm,+/-0.1%,1/16W,G,SMD0402 | KOA SPEER ELECTRONICS, INC. | RN731ETTP1050B25 | G | PWA BOM | In Old BOM |
|  |  |  | 61100SU00-012-G | RES,105 Ohm,+/-0.1%,1/16W,G,SMD0402 | WALSIN TECHNOLOGY CORPORATION | WF04U1050BTL | G | PWA BOM | In Old BOM |
|  |  |  | 61100SU00-011-G | RES,105 Ohm,+/-0.1%,1/16W,G,SMD0402 | YAGEO CORPORATION COMPONENT | RT0402BRD07105RL | G | PWA BOM | In Old BOM |
| 3 | R251,R252 | 2 | 610118100-017-G | RES,1.4KOhm,+/-1%,1/16W,G,SMD0402 | KOA SPEER ELECTRONICS, INC. | RK73H1ETTP1401F | G | PWA BOM | In New BOM |
|  |  |  | 610118100-012-G | RES,1.4KOhm,+/-1%,1/16W,G,SMD0402 | WALSIN TECHNOLOGY CORPORATION | WR04X1401FTL | G | PWA BOM | In New BOM |
|  |  |  | 610118100-011-G | RES,1.4KOhm,+/-1%,1/16W,G,SMD0402 | YAGEO CORPORATION COMPONENT | RC0402FR-071K4L | G | PWA BOM | In New BOM |
|  |  |  | 610118100-044-G | RES,1.4KOhm,+/-1%,1/16W,G,SMD0402 | TA-I TECHNOLOGY CO., LTD | RM04FTN1401 | G | PWA BOM | In New BOM |
|  |  |  | 610118100-024-G | RES,1.4KOhm,+/-1%,1/16W,G,SMD0402 | PANASONIC INDUSTRIAL CO.,LTD. | ERJ2RKF1401X | G | PWA BOM | In New BOM |
|  | R251,R252 | 2 | 610118100-017-G | RES,1.4KOhm,+/-1%,1/16W,G,SMD0402 | KOA SPEER ELECTRONICS, INC. | RK73H1ETTP1401F | G | PWA BOM | In Old BOM |
|  |  |  | 610118100-012-G | RES,1.4KOhm,+/-1%,1/16W,G,SMD0402 | WALSIN TECHNOLOGY CORPORATION | WR04X1401FTL |  | PWA BOM | In Old BOM |
|  |  |  | 610118100-011-G | RES,1.4KOhm,+/-1%,1/16W,G,SMD0402 | YAGEO CORPORATION COMPONENT | RC0402FR-071K4L |  | PWA BOM | In Old BOM |
|  |  |  | 610118100-044-G | RES,1.4KOhm,+/-1%,1/16W,G,SMD0402 | TA-I TECHNOLOGY CO., LTD | RM04FTN1401 |  | PWA BOM | In Old BOM |
| 4 | C2231 | 1 | 620109S00-023-G | CAP,4.7uF,+/-10%,X7R,10V,G,SMD0805 | TAIYO ELECTRIC IND.CO.LTD | LMK212B7475KG-T | G | PWA BOM | In New BOM |
|  |  |  | 620109S00-026-G | CAP,4.7uF,+/-10%,X7R,10V,G,SMD0805 | SAMSUNG SEMICONDUCTOR | CL21B475KPFNNNE | G | PWA BOM | In New BOM |
|  |  |  | 620109S00-015-G | CAP,4.7uF,+/-10%,X7R,10V,G,SMD0805 | MURATA ELEC. NORTH AMERICA | GRM21BR71A475K | G | PWA BOM | In New BOM |
|  | C2231 | 1 | 620109S00-015-G | CAP,4.7uF,+/-10%,X7R,10V,G,SMD0805 | MURATA ELEC. NORTH AMERICA | GRM21BR71A475K | G | PWA BOM | In Old BOM |
|  |  |  | 620109S00-023-G | CAP,4.7uF,+/-10%,X7R,10V,G,SMD0805 | TAIYO ELECTRIC IND.CO.LTD | LMK212B7475KG-T | G | PWA BOM | In Old BOM |
|  |  |  | 620109S00-026-G | CAP,4.7uF,+/-10%,X7R,10V,G,SMD0805 | SAMSUNG SEMICONDUCTOR | CL21B475KPFNNNE | G | PWA BOM | In Old BOM |
| ##### Change Revision |  |  |  |  |  |  |  |  |  |
| Sheet | REV OF BOM | CUSTOMER | CUSTOMER P/N | PWA PN | PWA DESCRIPTION | PWA REV | DATE | Remark |  |
| OOOOOOOOOOOOOOOOOOOOOOOOOOOOOOOOOOOOOOOOOOOOOOOOOOOOOOOOOOOOOOOOOOOOOOOOOOOOOOOOOOOOOOOOOO | OOOOOOOOOOOOOOOOOOOOOOOOOOOOOOOOOOOOOOOOOOOOOOOOOOOOOOOOOOOOOOOOOOOOOOOOOOOOOOOOOOOOOOOOOO | OOOOOOOOOOOOOOOOOOOOOOOOOOOOOOOOOOOOOOOOOOOOOOOOOOOOOOOOOOOOOOOOOOOOOOOOOOOOOOOOOOOOOOOOOO | OOOOOOOOOOOOOOOOOOOOOOOOOOOOOOOOOOOOOOOOOOOOOOOOOOOOOOOOOOOOOOOOOOOOOOOOOOOOOOOOOOOOOOOOOO | OOOOOOOOOOOOOOOOOOOOOOOOOOOOOOOOOOOOOOOOOOOOOOOOOOOOOOOOOOOOOOOOOOOOOOOOOOOOOOOOOOOOOOOOOO | OOOOOOOOOOOOOOOOOOOOOOOOOOOOOOOOOOOOOOOOOOOOOOOOOOOOOOOOOOOOOOOOOOOOOOOOOOOOOOOOOOOOOOOOOO | OOOOOOOOOOOOOOOOOOOOOOOOOOOOOOOOOOOOOOOOOOOOOOOOOOOOOOOOOOOOOOOOOOOOOOOOOOOOOOOOOOOOOOOOOO | OOOOOOOOOOOOOOOOOOOOOOOOOOOOOOOOOOOOOOOOOOOOOOOOOOOOOOOOOOOOOOOOOOOOOOOOOOOOOOOOOOOOOOOOOO | OOOOOOOOOOOOOOOOOOOOOOOOOOOOOOOOOOOOOOOOOOOOOOOOOOOOOOOOOOOOOOOOOOOOOOOOOOOOOOOOOOOOOOOOOO | OOOOOOOOOOOOOOOOOOOOOOOOOOOOOOOOOOOOOOOOOOOOOOOOOOOOOOOOOOOOOOOOOOOOOOOOOOOOOOOOOOOOOOOOOO |
| Second Source Change |  |  |  |  |  |  |  |  |  |
| Item | Location | Change Type | Foxconn P/N | Part Description | Manufacturer Full Name | Manufacturer P/N | RoHS | Sheet |  |
| 1 | PSTR5,PFTR5,PETR5 |  | 61100QD00-017-G | RES,787 Ohm,+/-0.1%,1/16W,G,SMD0402 | KOA SPEER ELECTRONICS, INC. | RN731ETTP7870B25 | G | PWA BOM |  |
|  |  | NO | 61100QD00-011-G | RES,787 Ohm,+/-0.1%,1/16W,G,SMD0402 | YAGEO CORPORATION COMPONENT | RT0402BRD07787RL | G | PWA BOM |  |
|  |  | ADD | 61100QD00-044-G | RES,787 Ohm,+/-0.1%,1/16W,G,SMD0402 | TA-I TECHNOLOGY CO., LTD | RB04BTP7870 | G | PWA BOM |  |
|  |  | NO | 61100QD00-012-G | RES,787 Ohm,+/-0.1%,1/16W,G,SMD0402 | WALSIN TECHNOLOGY CORPORATION | WF04U7870BTL | G | PWA BOM |  |
| 2 | PSTR6,PFTR6,PETR6 |  | 61100SU00-017-G | RES,105 Ohm,+/-0.1%,1/16W,G,SMD0402 | KOA SPEER ELECTRONICS, INC. | RN731ETTP1050B25 | G | PWA BOM |  |
|  |  | NO | 61100SU00-011-G | RES,105 Ohm,+/-0.1%,1/16W,G,SMD0402 | YAGEO CORPORATION COMPONENT | RT0402BRD07105RL | G | PWA BOM |  |
|  |  | ADD | 61100SU00-044-G | RES,105 Ohm,+/-0.1%,1/16W,G,SMD0402 | TA-I TECHNOLOGY CO., LTD | RB04BTP1050 | G | PWA BOM |  |
|  |  | NO | 61100SU00-012-G | RES,105 Ohm,+/-0.1%,1/16W,G,SMD0402 | WALSIN TECHNOLOGY CORPORATION | WF04U1050BTL | G | PWA BOM |  |
| 3 | R251,R252 |  | 610118100-017-G | RES,1.4KOhm,+/-1%,1/16W,G,SMD0402 | KOA SPEER ELECTRONICS, INC. | RK73H1ETTP1401F | G | PWA BOM |  |
|  |  | NO | 610118100-012-G | RES,1.4KOhm,+/-1%,1/16W,G,SMD0402 | WALSIN TECHNOLOGY CORPORATION | WR04X1401FTL | G | PWA BOM |  |
|  |  | NO | 610118100-011-G | RES,1.4KOhm,+/-1%,1/16W,G,SMD0402 | YAGEO CORPORATION COMPONENT | RC0402FR-071K4L | G | PWA BOM |  |
|  |  | NO | 610118100-044-G | RES,1.4KOhm,+/-1%,1/16W,G,SMD0402 | TA-I TECHNOLOGY CO., LTD | RM04FTN1401 | G | PWA BOM |  |
|  |  | ADD | 610118100-024-G | RES,1.4KOhm,+/-1%,1/16W,G,SMD0402 | PANASONIC INDUSTRIAL CO.,LTD. | ERJ2RKF1401X | G | PWA BOM |  |
| OOOOOOOOOOOOOOOOOOOOOOOOOOOOOOOOOOOOOOOOOOOOOOOOOOOOOOOOOOOOOOOOOOOOOOOOOOOOOOOOOOOOOOOOOO | OOOOOOOOOOOOOOOOOOOOOOOOOOOOOOOOOOOOOOOOOOOOOOOOOOOOOOOOOOOOOOOOOOOOOOOOOOOOOOOOOOOOOOOOOO | OOOOOOOOOOOOOOOOOOOOOOOOOOOOOOOOOOOOOOOOOOOOOOOOOOOOOOOOOOOOOOOOOOOOOOOOOOOOOOOOOOOOOOOOOO | OOOOOOOOOOOOOOOOOOOOOOOOOOOOOOOOOOOOOOOOOOOOOOOOOOOOOOOOOOOOOOOOOOOOOOOOOOOOOOOOOOOOOOOOOO | OOOOOOOOOOOOOOOOOOOOOOOOOOOOOOOOOOOOOOOOOOOOOOOOOOOOOOOOOOOOOOOOOOOOOOOOOOOOOOOOOOOOOOOOOO | OOOOOOOOOOOOOOOOOOOOOOOOOOOOOOOOOOOOOOOOOOOOOOOOOOOOOOOOOOOOOOOOOOOOOOOOOOOOOOOOOOOOOOOOOO | OOOOOOOOOOOOOOOOOOOOOOOOOOOOOOOOOOOOOOOOOOOOOOOOOOOOOOOOOOOOOOOOOOOOOOOOOOOOOOOOOOOOOOOOOO | OOOOOOOOOOOOOOOOOOOOOOOOOOOOOOOOOOOOOOOOOOOOOOOOOOOOOOOOOOOOOOOOOOOOOOOOOOOOOOOOOOOOOOOOOO | OOOOOOOOOOOOOOOOOOOOOOOOOOOOOOOOOOOOOOOOOOOOOOOOOOOOOOOOOOOOOOOOOOOOOOOOOOOOOOOOOOOOOOOOOO | OOOOOOOOOOOOOOOOOOOOOOOOOOOOOOOOOOOOOOOOOOOOOOOOOOOOOOOOOOOOOOOOOOOOOOOOOOOOOOOOOOOOOOOOOO |
| Master Materials Change |  |  |  |  |  |  |  |  |  |
| Item | Foxconn P/N | Orig._Usage | New_Usage | Part Description | Manufacturer Full Name | Manufacturer P/N | RoHS | Location | Sheet |
| 1 | 620109S00-023-G | 0 | 1 | CAP,4.7uF,+/-10%,X7R,10V,G,SMD0805 | TAIYO ELECTRIC IND.CO.LTD | LMK212B7475KG-T | G | (+)C2231 | PWA BOM |
|  | 620109S00-026-G |  |  | CAP,4.7uF,+/-10%,X7R,10V,G,SMD0805 | SAMSUNG SEMICONDUCTOR | CL21B475KPFNNNE |  |  | PWA BOM |
|  | 620109S00-015-G |  |  | CAP,4.7uF,+/-10%,X7R,10V,G,SMD0805 | MURATA ELEC. NORTH AMERICA | GRM21BR71A475K |  |  | PWA BOM |
| 2 | 620109S00-015-G | 1 | 0 | CAP,4.7uF,+/-10%,X7R,10V,G,SMD0805 | MURATA ELEC. NORTH AMERICA | GRM21BR71A475K | G | (-)C2231 | PWA BOM |
|  | 620109S00-023-G |  |  | CAP,4.7uF,+/-10%,X7R,10V,G,SMD0805 | TAIYO ELECTRIC IND.CO.LTD | LMK212B7475KG-T |  |  | PWA BOM |
|  | 620109S00-026-G |  |  | CAP,4.7uF,+/-10%,X7R,10V,G,SMD0805 | SAMSUNG SEMICONDUCTOR | CL21B475KPFNNNE |  |  | PWA BOM |
| OOOOOOOOOOOOOOOOOOOOOOOOOOOOOOOOOOOOOOOOOOOOOOOOOOOOOOOOOOOOOOOOOOOOOOOOOOOOOOOOOOOOOOOOOO | OOOOOOOOOOOOOOOOOOOOOOOOOOOOOOOOOOOOOOOOOOOOOOOOOOOOOOOOOOOOOOOOOOOOOOOOOOOOOOOOOOOOOOOOOO | OOOOOOOOOOOOOOOOOOOOOOOOOOOOOOOOOOOOOOOOOOOOOOOOOOOOOOOOOOOOOOOOOOOOOOOOOOOOOOOOOOOOOOOOOO | OOOOOOOOOOOOOOOOOOOOOOOOOOOOOOOOOOOOOOOOOOOOOOOOOOOOOOOOOOOOOOOOOOOOOOOOOOOOOOOOOOOOOOOOOO | OOOOOOOOOOOOOOOOOOOOOOOOOOOOOOOOOOOOOOOOOOOOOOOOOOOOOOOOOOOOOOOOOOOOOOOOOOOOOOOOOOOOOOOOOO | OOOOOOOOOOOOOOOOOOOOOOOOOOOOOOOOOOOOOOOOOOOOOOOOOOOOOOOOOOOOOOOOOOOOOOOOOOOOOOOOOOOOOOOOOO | OOOOOOOOOOOOOOOOOOOOOOOOOOOOOOOOOOOOOOOOOOOOOOOOOOOOOOOOOOOOOOOOOOOOOOOOOOOOOOOOOOOOOOOOOO | OOOOOOOOOOOOOOOOOOOOOOOOOOOOOOOOOOOOOOOOOOOOOOOOOOOOOOOOOOOOOOOOOOOOOOOOOOOOOOOOOOOOOOOOOO | OOOOOOOOOOOOOOOOOOOOOOOOOOOOOOOOOOOOOOOOOOOOOOOOOOOOOOOOOOOOOOOOOOOOOOOOOOOOOOOOOOOOOOOOOO | OOOOOOOOOOOOOOOOOOOOOOOOOOOOOOOOOOOOOOOOOOOOOOOOOOOOOOOOOOOOOOOOOOOOOOOOOOOOOOOOOOOOOOOOOO |
| TLA Parts Change |  |  |  |  |  |  |  |  |  |
| Item | Foxconn P/N | Qty | Part Description | Manufacturer Full Name | Manufacturer P/N | RoHS | Location | Remark | BOM |
| BOM Change List Date:Tue Sep 12 17:59:51 GMT+08:00 2017 |  |  |  |  |  |  |  |  |  |
| New BOM file : E:\barreleye g2\0912\BPX24 EXPANDER\Barreleye-G2_Tri-mode BPX24-DVT-X01-BOM-X06-20170912.xls |  |  |  |  |  |  |  |  |  |
| Old BOM file : E:\barreleye g2\0912\BPX24 EXPANDER\BPX24 0906.xls |  |  |  |  |  |  |  |  |  |
| ##### Add Parts |  |  |  |  |  |  |  |  |  |
| Item | Location | Qty | Foxconn P/N | Part Description | Manufacturer Full Name | Manufacturer P/N | RoHS | Sheet |  |
| ##### Remove Parts |  |  |  |  |  |  |  |  |  |
| Item | Location | Qty | Foxconn P/N | Part Description | Manufacturer Full Name | Manufacturer P/N | RoHS | Sheet |  |
| ##### Change Parts |  |  |  |  |  |  |  |  |  |
| Item | Location | Qty | Foxconn P/N | Part Description | Manufacturer Full Name | Manufacturer P/N | RoHS | Sheet | Remark |
| 1 | R1314,R1786,R1789,R1790,R1792,R1794,R1797,R1798,R1801,R1802,R1805,R1806,R1809,R1810,R1813,R1814,R1817,R1818,R1821,R1822,R1825,R1826,R1829,R1830 | 24 | 610100T00-017-G | RES,1KOhm,+/-5%,1/16W,G,SMD0402 | KOA SPEER ELECTRONICS, INC. | RK73B1ETTP102J | G | PWA BOM | In New BOM |
|  |  |  | 610100T00-012-G | RES,1KOhm,+/-5%,1/16W,G,SMD0402 | WALSIN TECHNOLOGY CORPORATION | WR04X102JTL | G | PWA BOM | In New BOM |
|  |  |  | 610100T00-011-G | RES,1KOhm,+/-5%,1/16W,G,SMD0402 | YAGEO CORPORATION COMPONENT | RC0402JR-071KL | G | PWA BOM | In New BOM |
|  |  |  | 610100T00-044-G | RES,1KOhm,+/-5%,1/16W,G,SMD0402 | TA-I TECHNOLOGY CO., LTD | RM04JTN102 | G | PWA BOM | In New BOM |
|  |  |  | 610100T00-024-G | RES,1KOhm,+/-5%,1/16W,G,SMD0402 | PANASONIC INDUSTRIAL CO.,LTD. | ERJ2GEJ102X | G | PWA BOM | In New BOM |
|  | R1314,R1786,R1789,R1790,R1792,R1794,R1797,R1798,R1801,R1802,R1805,R1806,R1809,R1810,R1813,R1814,R1817,R1818,R1821,R1822,R1825,R1826,R1829,R1830 | 24 | 61011FA00-017-G | RES,1.02KOhm,+/-1%,1/16W,G,SMD0402 | KOA SPEER ELECTRONICS, INC. | RK73H1ETTP1021F | G | PWA BOM | In Old BOM |
|  |  |  | 61011FA00-011-G | RES,1.02KOhm,+/-1%,1/16W,G,SMD0402 | YAGEO CORPORATION COMPONENT | RC0402FR-071K02L | G | PWA BOM | In Old BOM |
|  |  |  | 61011FA00-012-G | RES,1.02KOhm,+/-1%,1/16W,G,SMD0402 | WALSIN TECHNOLOGY CORPORATION | WR04X1021FTL | G | PWA BOM | In Old BOM |
|  |  |  | 61011FA00-044-G | RES,1.02KOhm,+/-1%,1/16W,G,SMD0402 | TA-I TECHNOLOGY CO., LTD | RM04FTN1021 | G | PWA BOM | In Old BOM |
| 2 | J_CPLD_JTAG | 1 | 3406B6F00-317-G | CONN,Header,WTB,2X3,R/A,Bla,2.5mm,15u,G,SMD-6 | MOLEX INCORPORATED | 15-91-2065 | G | PWA BOM | In New BOM |
|  | J_CPLD_JTAG | 1 | ZP91-0155C-1221 | CONN,Header,WTB,2X3,R/A,Bla,2.5mm,15u,G,SMD-6 | CENLINK | ZP91-0155C-1221 | G | PWA BOM | In Old BOM |
| ##### Change Revision |  |  |  |  |  |  |  |  |  |
| Sheet | REV OF BOM | CUSTOMER | CUSTOMER P/N | PWA PN | PWA DESCRIPTION | PWA REV | DATE | Remark |  |
| OOOOOOOOOOOOOOOOOOOOOOOOOOOOOOOOOOOOOOOOOOOOOOOOOOOOOOOOOOOOOOOOOOOOOOOOOOOOOOOOOOOOOOOOOO | OOOOOOOOOOOOOOOOOOOOOOOOOOOOOOOOOOOOOOOOOOOOOOOOOOOOOOOOOOOOOOOOOOOOOOOOOOOOOOOOOOOOOOOOOO | OOOOOOOOOOOOOOOOOOOOOOOOOOOOOOOOOOOOOOOOOOOOOOOOOOOOOOOOOOOOOOOOOOOOOOOOOOOOOOOOOOOOOOOOOO | OOOOOOOOOOOOOOOOOOOOOOOOOOOOOOOOOOOOOOOOOOOOOOOOOOOOOOOOOOOOOOOOOOOOOOOOOOOOOOOOOOOOOOOOOO | OOOOOOOOOOOOOOOOOOOOOOOOOOOOOOOOOOOOOOOOOOOOOOOOOOOOOOOOOOOOOOOOOOOOOOOOOOOOOOOOOOOOOOOOOO | OOOOOOOOOOOOOOOOOOOOOOOOOOOOOOOOOOOOOOOOOOOOOOOOOOOOOOOOOOOOOOOOOOOOOOOOOOOOOOOOOOOOOOOOOO | OOOOOOOOOOOOOOOOOOOOOOOOOOOOOOOOOOOOOOOOOOOOOOOOOOOOOOOOOOOOOOOOOOOOOOOOOOOOOOOOOOOOOOOOOO | OOOOOOOOOOOOOOOOOOOOOOOOOOOOOOOOOOOOOOOOOOOOOOOOOOOOOOOOOOOOOOOOOOOOOOOOOOOOOOOOOOOOOOOOOO | OOOOOOOOOOOOOOOOOOOOOOOOOOOOOOOOOOOOOOOOOOOOOOOOOOOOOOOOOOOOOOOOOOOOOOOOOOOOOOOOOOOOOOOOOO | OOOOOOOOOOOOOOOOOOOOOOOOOOOOOOOOOOOOOOOOOOOOOOOOOOOOOOOOOOOOOOOOOOOOOOOOOOOOOOOOOOOOOOOOOO |
| Second Source Change |  |  |  |  |  |  |  |  |  |
| Item | Location | Change Type | Foxconn P/N | Part Description | Manufacturer Full Name | Manufacturer P/N | RoHS | Sheet |  |
| OOOOOOOOOOOOOOOOOOOOOOOOOOOOOOOOOOOOOOOOOOOOOOOOOOOOOOOOOOOOOOOOOOOOOOOOOOOOOOOOOOOOOOOOOO | OOOOOOOOOOOOOOOOOOOOOOOOOOOOOOOOOOOOOOOOOOOOOOOOOOOOOOOOOOOOOOOOOOOOOOOOOOOOOOOOOOOOOOOOOO | OOOOOOOOOOOOOOOOOOOOOOOOOOOOOOOOOOOOOOOOOOOOOOOOOOOOOOOOOOOOOOOOOOOOOOOOOOOOOOOOOOOOOOOOOO | OOOOOOOOOOOOOOOOOOOOOOOOOOOOOOOOOOOOOOOOOOOOOOOOOOOOOOOOOOOOOOOOOOOOOOOOOOOOOOOOOOOOOOOOOO | OOOOOOOOOOOOOOOOOOOOOOOOOOOOOOOOOOOOOOOOOOOOOOOOOOOOOOOOOOOOOOOOOOOOOOOOOOOOOOOOOOOOOOOOOO | OOOOOOOOOOOOOOOOOOOOOOOOOOOOOOOOOOOOOOOOOOOOOOOOOOOOOOOOOOOOOOOOOOOOOOOOOOOOOOOOOOOOOOOOOO | OOOOOOOOOOOOOOOOOOOOOOOOOOOOOOOOOOOOOOOOOOOOOOOOOOOOOOOOOOOOOOOOOOOOOOOOOOOOOOOOOOOOOOOOOO | OOOOOOOOOOOOOOOOOOOOOOOOOOOOOOOOOOOOOOOOOOOOOOOOOOOOOOOOOOOOOOOOOOOOOOOOOOOOOOOOOOOOOOOOOO | OOOOOOOOOOOOOOOOOOOOOOOOOOOOOOOOOOOOOOOOOOOOOOOOOOOOOOOOOOOOOOOOOOOOOOOOOOOOOOOOOOOOOOOOOO | OOOOOOOOOOOOOOOOOOOOOOOOOOOOOOOOOOOOOOOOOOOOOOOOOOOOOOOOOOOOOOOOOOOOOOOOOOOOOOOOOOOOOOOOOO |
| Master Materials Change |  |  |  |  |  |  |  |  |  |
| Item | Foxconn P/N | Orig._Usage | New_Usage | Part Description | Manufacturer Full Name | Manufacturer P/N | RoHS | Location | Sheet |
| 1 | 610100T00-017-G | 17 | 41 | RES,1KOhm,+/-5%,1/16W,G,SMD0402 | KOA SPEER ELECTRONICS, INC. | RK73B1ETTP102J | G | (+)R1314,R1786,R1789,R1790,R1792,R1794,R1797,R1798,R1801,R1802,R1805,R1806,R1809,R1810,R1813,R1814,R1817,R1818,R1821,R1822,R1825,R1826,R1829,R1830 | PWA BOM |
|  | 610100T00-012-G |  |  | RES,1KOhm,+/-5%,1/16W,G,SMD0402 | WALSIN TECHNOLOGY CORPORATION | WR04X102JTL |  |  | PWA BOM |
|  | 610100T00-011-G |  |  | RES,1KOhm,+/-5%,1/16W,G,SMD0402 | YAGEO CORPORATION COMPONENT | RC0402JR-071KL |  |  | PWA BOM |
|  | 610100T00-044-G |  |  | RES,1KOhm,+/-5%,1/16W,G,SMD0402 | TA-I TECHNOLOGY CO., LTD | RM04JTN102 |  |  | PWA BOM |
|  | 610100T00-024-G |  |  | RES,1KOhm,+/-5%,1/16W,G,SMD0402 | PANASONIC INDUSTRIAL CO.,LTD. | ERJ2GEJ102X |  |  | PWA BOM |
| 2 | 3406B6F00-317-G | 0 | 1 | CONN,Header,WTB,2X3,R/A,Bla,2.5mm,15u,G,SMD-6 | MOLEX INCORPORATED | 15-91-2065 | G | (+)J_CPLD_JTAG | PWA BOM |
| 3 | 61011FA00-017-G | 24 | 0 | RES,1.02KOhm,+/-1%,1/16W,G,SMD0402 | KOA SPEER ELECTRONICS, INC. | RK73H1ETTP1021F | G | (-)R1314,R1786,R1789,R1790,R1792,R1794,R1797,R1798,R1801,R1802,R1805,R1806,R1809,R1810,R1813,R1814,R1817,R1818,R1821,R1822,R1825,R1826,R1829,R1830 | PWA BOM |
|  | 61011FA00-011-G |  |  | RES,1.02KOhm,+/-1%,1/16W,G,SMD0402 | YAGEO CORPORATION COMPONENT | RC0402FR-071K02L |  |  | PWA BOM |
|  | 61011FA00-012-G |  |  | RES,1.02KOhm,+/-1%,1/16W,G,SMD0402 | WALSIN TECHNOLOGY CORPORATION | WR04X1021FTL |  |  | PWA BOM |
|  | 61011FA00-044-G |  |  | RES,1.02KOhm,+/-1%,1/16W,G,SMD0402 | TA-I TECHNOLOGY CO., LTD | RM04FTN1021 |  |  | PWA BOM |
| 4 | ZP91-0155C-1221 | 1 | 0 | CONN,Header,WTB,2X3,R/A,Bla,2.5mm,15u,G,SMD-6 | CENLINK | ZP91-0155C-1221 | G | (-)J_CPLD_JTAG | PWA BOM |
| OOOOOOOOOOOOOOOOOOOOOOOOOOOOOOOOOOOOOOOOOOOOOOOOOOOOOOOOOOOOOOOOOOOOOOOOOOOOOOOOOOOOOOOOOO | OOOOOOOOOOOOOOOOOOOOOOOOOOOOOOOOOOOOOOOOOOOOOOOOOOOOOOOOOOOOOOOOOOOOOOOOOOOOOOOOOOOOOOOOOO | OOOOOOOOOOOOOOOOOOOOOOOOOOOOOOOOOOOOOOOOOOOOOOOOOOOOOOOOOOOOOOOOOOOOOOOOOOOOOOOOOOOOOOOOOO | OOOOOOOOOOOOOOOOOOOOOOOOOOOOOOOOOOOOOOOOOOOOOOOOOOOOOOOOOOOOOOOOOOOOOOOOOOOOOOOOOOOOOOOOOO | OOOOOOOOOOOOOOOOOOOOOOOOOOOOOOOOOOOOOOOOOOOOOOOOOOOOOOOOOOOOOOOOOOOOOOOOOOOOOOOOOOOOOOOOOO | OOOOOOOOOOOOOOOOOOOOOOOOOOOOOOOOOOOOOOOOOOOOOOOOOOOOOOOOOOOOOOOOOOOOOOOOOOOOOOOOOOOOOOOOOO | OOOOOOOOOOOOOOOOOOOOOOOOOOOOOOOOOOOOOOOOOOOOOOOOOOOOOOOOOOOOOOOOOOOOOOOOOOOOOOOOOOOOOOOOOO | OOOOOOOOOOOOOOOOOOOOOOOOOOOOOOOOOOOOOOOOOOOOOOOOOOOOOOOOOOOOOOOOOOOOOOOOOOOOOOOOOOOOOOOOOO | OOOOOOOOOOOOOOOOOOOOOOOOOOOOOOOOOOOOOOOOOOOOOOOOOOOOOOOOOOOOOOOOOOOOOOOOOOOOOOOOOOOOOOOOOO |  |
| TLA Parts Change |  |  |  |  |  |  |  |  |  |
| Item | Foxconn P/N | Qty | Part Description | Manufacturer Full Name | Manufacturer P/N | RoHS | Location | Remark |  |
| BOM Change List Date:Thu Sep 14 13:43:02 GMT+08:00 2017 |  |  |  |  |  |  |  |  |  |
| New BOM file : E:\barreleye g2\0913\foxbis\BPX24 13.xls |  |  |  |  |  |  |  |  |  |
| Old BOM file : E:\barreleye g2\0913\foxbis\BPX24 12.xls |  |  |  |  |  |  |  |  |  |
| ##### Add Parts |  |  |  |  |  |  |  |  |  |
| Item | Location | Qty | Foxconn P/N | Part Description | Manufacturer Full Name | Manufacturer P/N | RoHS | Sheet |  |
| ##### Remove Parts |  |  |  |  |  |  |  |  |  |
| Item | Location | Qty | Foxconn P/N | Part Description | Manufacturer Full Name | Manufacturer P/N | RoHS | Sheet |  |
| ##### Change Parts |  |  |  |  |  |  |  |  |  |
| Item | Location | Qty | Foxconn P/N | Part Description | Manufacturer Full Name | Manufacturer P/N | RoHS | Sheet | Remark |
| 1 | U_BP_FRU1 | 1 | 41040HW00-191-G | EEPROM,AT24C02D-SSHM-T,1.7~3.6V,2K,I2C,G,SOIC-8,SMD | ATMEL CORPORATION | AT24C02D-SSHM-T | G | PWA BOM | In New BOM |
|  |  |  | 410401W00-214-G | EEPROM,M24C02-WMN6TP,2.5~5.5V,256*8,I2C,G,SOIC-8,SMD | ST MICRO ELECTRONICS,INC | M24C02-WMN6TP |  | PWA BOM | In New BOM |
|  |  |  | 41040J500-232-G | EEPROM,24AA024T-I/SN,1.7V~5.5V,2K,I2C,G,SOIC-8,SMD | MICROCHIP TECHNOLOGY INC | 24AA024T-I/SN |  | PWA BOM | In New BOM |
|  | U_BP_FRU1 | 1 | 41040B600-191-G | EEPROM,AT24C02C-SSHM-T,1.7~5.5V,2K,I2C,G,SOIC-8,SMD | ATMEL CORPORATION | AT24C02C-SSHM-T | G | PWA BOM | In Old BOM |
| ##### Change Revision |  |  |  |  |  |  |  |  |  |
| Sheet | REV OF BOM | CUSTOMER | CUSTOMER P/N | PWA PN | PWA DESCRIPTION | PWA REV | DATE | Remark |  |
| OOOOOOOOOOOOOOOOOOOOOOOOOOOOOOOOOOOOOOOOOOOOOOOOOOOOOOOOOOOOOOOOOOOOOOOOOOOOOOOOOOOOOOOOOO | OOOOOOOOOOOOOOOOOOOOOOOOOOOOOOOOOOOOOOOOOOOOOOOOOOOOOOOOOOOOOOOOOOOOOOOOOOOOOOOOOOOOOOOOOO | OOOOOOOOOOOOOOOOOOOOOOOOOOOOOOOOOOOOOOOOOOOOOOOOOOOOOOOOOOOOOOOOOOOOOOOOOOOOOOOOOOOOOOOOOO | OOOOOOOOOOOOOOOOOOOOOOOOOOOOOOOOOOOOOOOOOOOOOOOOOOOOOOOOOOOOOOOOOOOOOOOOOOOOOOOOOOOOOOOOOO | OOOOOOOOOOOOOOOOOOOOOOOOOOOOOOOOOOOOOOOOOOOOOOOOOOOOOOOOOOOOOOOOOOOOOOOOOOOOOOOOOOOOOOOOOO | OOOOOOOOOOOOOOOOOOOOOOOOOOOOOOOOOOOOOOOOOOOOOOOOOOOOOOOOOOOOOOOOOOOOOOOOOOOOOOOOOOOOOOOOOO | OOOOOOOOOOOOOOOOOOOOOOOOOOOOOOOOOOOOOOOOOOOOOOOOOOOOOOOOOOOOOOOOOOOOOOOOOOOOOOOOOOOOOOOOOO | OOOOOOOOOOOOOOOOOOOOOOOOOOOOOOOOOOOOOOOOOOOOOOOOOOOOOOOOOOOOOOOOOOOOOOOOOOOOOOOOOOOOOOOOOO | OOOOOOOOOOOOOOOOOOOOOOOOOOOOOOOOOOOOOOOOOOOOOOOOOOOOOOOOOOOOOOOOOOOOOOOOOOOOOOOOOOOOOOOOOO | OOOOOOOOOOOOOOOOOOOOOOOOOOOOOOOOOOOOOOOOOOOOOOOOOOOOOOOOOOOOOOOOOOOOOOOOOOOOOOOOOOOOOOOOOO |
| Second Source Change |  |  |  |  |  |  |  |  |  |
| Item | Location | Change Type | Foxconn P/N | Part Description | Manufacturer Full Name | Manufacturer P/N | RoHS | Sheet |  |
| OOOOOOOOOOOOOOOOOOOOOOOOOOOOOOOOOOOOOOOOOOOOOOOOOOOOOOOOOOOOOOOOOOOOOOOOOOOOOOOOOOOOOOOOOO | OOOOOOOOOOOOOOOOOOOOOOOOOOOOOOOOOOOOOOOOOOOOOOOOOOOOOOOOOOOOOOOOOOOOOOOOOOOOOOOOOOOOOOOOOO | OOOOOOOOOOOOOOOOOOOOOOOOOOOOOOOOOOOOOOOOOOOOOOOOOOOOOOOOOOOOOOOOOOOOOOOOOOOOOOOOOOOOOOOOOO | OOOOOOOOOOOOOOOOOOOOOOOOOOOOOOOOOOOOOOOOOOOOOOOOOOOOOOOOOOOOOOOOOOOOOOOOOOOOOOOOOOOOOOOOOO | OOOOOOOOOOOOOOOOOOOOOOOOOOOOOOOOOOOOOOOOOOOOOOOOOOOOOOOOOOOOOOOOOOOOOOOOOOOOOOOOOOOOOOOOOO | OOOOOOOOOOOOOOOOOOOOOOOOOOOOOOOOOOOOOOOOOOOOOOOOOOOOOOOOOOOOOOOOOOOOOOOOOOOOOOOOOOOOOOOOOO | OOOOOOOOOOOOOOOOOOOOOOOOOOOOOOOOOOOOOOOOOOOOOOOOOOOOOOOOOOOOOOOOOOOOOOOOOOOOOOOOOOOOOOOOOO | OOOOOOOOOOOOOOOOOOOOOOOOOOOOOOOOOOOOOOOOOOOOOOOOOOOOOOOOOOOOOOOOOOOOOOOOOOOOOOOOOOOOOOOOOO | OOOOOOOOOOOOOOOOOOOOOOOOOOOOOOOOOOOOOOOOOOOOOOOOOOOOOOOOOOOOOOOOOOOOOOOOOOOOOOOOOOOOOOOOOO | OOOOOOOOOOOOOOOOOOOOOOOOOOOOOOOOOOOOOOOOOOOOOOOOOOOOOOOOOOOOOOOOOOOOOOOOOOOOOOOOOOOOOOOOOO |
| Master Materials Change |  |  |  |  |  |  |  |  |  |
| Item | Foxconn P/N | Orig._Usage | New_Usage | Part Description | Manufacturer Full Name | Manufacturer P/N | RoHS | Location | Sheet |
| 1 | 41040HW00-191-G | 0 | 1 | EEPROM,AT24C02D-SSHM-T,1.7~3.6V,2K,I2C,G,SOIC-8,SMD | ATMEL CORPORATION | AT24C02D-SSHM-T | G | (+)U_BP_FRU1 | PWA BOM |
|  | 410401W00-214-G |  |  | EEPROM,M24C02-WMN6TP,2.5~5.5V,256*8,I2C,G,SOIC-8,SMD | ST MICRO ELECTRONICS,INC | M24C02-WMN6TP |  |  | PWA BOM |
|  | 41040J500-232-G |  |  | EEPROM,24AA024T-I/SN,1.7V~5.5V,2K,I2C,G,SOIC-8,SMD | MICROCHIP TECHNOLOGY INC | 24AA024T-I/SN |  |  | PWA BOM |
| 2 | 41040B600-191-G | 1 | 0 | EEPROM,AT24C02C-SSHM-T,1.7~5.5V,2K,I2C,G,SOIC-8,SMD | ATMEL CORPORATION | AT24C02C-SSHM-T | G | (-)U_BP_FRU1 | PWA BOM |
| OOOOOOOOOOOOOOOOOOOOOOOOOOOOOOOOOOOOOOOOOOOOOOOOOOOOOOOOOOOOOOOOOOOOOOOOOOOOOOOOOOOOOOOOOO | OOOOOOOOOOOOOOOOOOOOOOOOOOOOOOOOOOOOOOOOOOOOOOOOOOOOOOOOOOOOOOOOOOOOOOOOOOOOOOOOOOOOOOOOOO | OOOOOOOOOOOOOOOOOOOOOOOOOOOOOOOOOOOOOOOOOOOOOOOOOOOOOOOOOOOOOOOOOOOOOOOOOOOOOOOOOOOOOOOOOO | OOOOOOOOOOOOOOOOOOOOOOOOOOOOOOOOOOOOOOOOOOOOOOOOOOOOOOOOOOOOOOOOOOOOOOOOOOOOOOOOOOOOOOOOOO | OOOOOOOOOOOOOOOOOOOOOOOOOOOOOOOOOOOOOOOOOOOOOOOOOOOOOOOOOOOOOOOOOOOOOOOOOOOOOOOOOOOOOOOOOO | OOOOOOOOOOOOOOOOOOOOOOOOOOOOOOOOOOOOOOOOOOOOOOOOOOOOOOOOOOOOOOOOOOOOOOOOOOOOOOOOOOOOOOOOOO | OOOOOOOOOOOOOOOOOOOOOOOOOOOOOOOOOOOOOOOOOOOOOOOOOOOOOOOOOOOOOOOOOOOOOOOOOOOOOOOOOOOOOOOOOO | OOOOOOOOOOOOOOOOOOOOOOOOOOOOOOOOOOOOOOOOOOOOOOOOOOOOOOOOOOOOOOOOOOOOOOOOOOOOOOOOOOOOOOOOOO | OOOOOOOOOOOOOOOOOOOOOOOOOOOOOOOOOOOOOOOOOOOOOOOOOOOOOOOOOOOOOOOOOOOOOOOOOOOOOOOOOOOOOOOOOO | OOOOOOOOOOOOOOOOOOOOOOOOOOOOOOOOOOOOOOOOOOOOOOOOOOOOOOOOOOOOOOOOOOOOOOOOOOOOOOOOOOOOOOOOOO |
| TLA Parts Change |  |  |  |  |  |  |  |  |  |
| Item | Foxconn P/N | Qty | Part Description | Manufacturer Full Name | Manufacturer P/N | RoHS | Location | Remark | BOM |
| BOM Change List Date:Fri Sep 22 11:48:38 GMT+08:00 2017 |  |  |  |  |  |  |  |  |  |
| New BOM file : C:\<user>\Barreleye-G2_Tri-mode BPX24-DVT-X01-BOM-X06-20170922.xls |  |  |  |  |  |  |  |  |  |
| Old BOM file : C:\<user>\BPX24 0914.xls |  |  |  |  |  |  |  |  |  |
| ##### Add Parts |  |  |  |  |  |  |  |  |  |
| Item | Location | Qty | Foxconn P/N | Part Description | Manufacturer Full Name | Manufacturer P/N | RoHS | Sheet |  |
| 1 | C2272 | 1 | 620101T02-015-G | CAP,100nF,+/-10%,X7R,16V,G,SMD0402 | MURATA ELEC. NORTH AMERICA | GRM155R71C104K | G | PWA BOM |  |
|  |  |  | 620101T00-012-G | CAP,100nF,+/-10%,X7R,16V,G,SMD0402 | WALSIN TECHNOLOGY CORPORATION | 0402B104K160CT | G | PWA BOM |  |
|  |  |  | 620101T00-026-G | CAP,100nF,+/-10%,X7R,16V,G,SMD0402 | SAMSUNG SEMICONDUCTOR | CL05B104KO5NNNC | G | PWA BOM |  |
|  |  |  | 620101T00-015-G | CAP,100nF,+/-10%,X7R,16V,G,SMD0402 | MURATA ELEC. NORTH AMERICA | GRM155R71C104KA88D | G | PWA BOM |  |
| 2 | R2158 | 1 | 610107A00-017-G | RES,0 Ohm,+/-5%,1/16W,G,SMD0402 | KOA SPEER ELECTRONICS, INC. | RK73Z1ETTP | G | PWA BOM |  |
|  |  |  | 610107A00-012-G | RES,0 Ohm,+/-5%,1/16W,G,SMD0402 | WALSIN TECHNOLOGY CORPORATION | WR04X000PTL | G | PWA BOM |  |
|  |  |  | 610107A00-011-G | RES,0 Ohm,+/-5%,1/16W,G,SMD0402 | YAGEO CORPORATION COMPONENT | RC0402JR-070RL | G | PWA BOM |  |
|  |  |  | 610107A00-044-G | RES,0 Ohm,+/-5%,1/16W,G,SMD0402 | TA-I TECHNOLOGY CO., LTD | RM04JTN0 | G | PWA BOM |  |
|  |  |  | 610107A00-024-G | RES,0 Ohm,+/-5%,1/16W,G,SMD0402 | PANASONIC INDUSTRIAL CO.,LTD. | ERJ2GE0R00X | G | PWA BOM |  |
|  |  |  | 610107A00-029-G | RES,0 Ohm,+/-5%,1/16W,G,SMD0402 | VISHAY ENTER TECHNO LOGY.INC | CRCW04020000Z0ED | G | PWA BOM |  |
| 3 | U5 | 1 | 310101400-031-G | IC,Gate&Inverter,74LVC1G08GW,1.65~5.5V,G,SOT353-5,SMD | NXP SEMICONDUCTORS | 74LVC1G08GW | G | PWA BOM |  |
|  |  |  | 310103J00-223-G | IC,Gate&Inverter,NL17SZ08DFT2G,1.65~5.5V,G,SOT353-5,SMD | ON SEMICONDUCTOR CORP | NL17SZ08DFT2G | G | PWA BOM |  |
|  |  |  | 31010J400-131-G | IC,Gate&Inverter,TC7SZ08FU,1.8~5.5V,G,SSOP-5,SMD | TOSHIBA ELECTRONICS ASIA LTD | TC7SZ08FU | G | PWA BOM |  |
| ##### Remove Parts |  |  |  |  |  |  |  |  |  |
| Item | Location | Qty | Foxconn P/N | Part Description | Manufacturer Full Name | Manufacturer P/N | RoHS | Sheet |  |
| ##### Change Parts |  |  |  |  |  |  |  |  |  |
| Item | Location | Qty | Foxconn P/N | Part Description | Manufacturer Full Name | Manufacturer P/N | RoHS | Sheet | Remark |
| 1 | C2268,C2269 | 2 | 62012UW00-015-G | CAP,6.8pF,+/-0.05pF,NPO(C0G),25V,G,SMD0402 | MURATA ELEC. NORTH AMERICA | GRM1555C1E6R8WA01D | G | PWA BOM | In New BOM |
|  |  |  | 62012UW00-012-G | CAP,6.8pF,+/-0.05pF,NPO(C0G),25V,G,SMD0402 | WALSIN TECHNOLOGY CORPORATION | 0402N6R8A250CT |  | PWA BOM | In New BOM |
|  | C2268,C2269 | 2 | 62012UW00-015-G | CAP,6.8pF,+/-0.05pF,NPO(C0G),25V,G,SMD0402 | MURATA ELEC. NORTH AMERICA | GRM1555C1E6R8WA01D | G | PWA BOM | In Old BOM |
| 2 | R875,R877,R879,R881,R883,R885,R887,R889,R891,R893,R895,R897,R899,R901,R903,R905,R907,R909,R911,R913,R915,R917,R919,R921 | 24 | 61015K700-017-G | RES,3.3 Ohm,+/-5%,1/2W,G,SMD1210 | KOA SPEER ELECTRONICS, INC. | RK73B2ETTD3R3J | G | PWA BOM | In New BOM |
|  |  |  | 61015K700-011-G | RES,3.3 Ohm,+/-5%,1/2W,G,SMD1210 | YAGEO CORPORATION COMPONENT | RC1210JR-073R3L |  | PWA BOM | In New BOM |
|  | R875,R877,R879,R881,R883,R885,R887,R889,R891,R893,R895,R897,R899,R901,R903,R905,R907,R909,R911,R913,R915,R917,R919,R921 | 24 | 61015K700-017-G | RES,3.3 Ohm,+/-5%,1/2W,G,SMD1210 | KOA SPEER ELECTRONICS, INC. | RK73B2ETTD3R3J | G | PWA BOM | In Old BOM |
| 3 | R2060 | 1 | 610154800-017-G | RES,1 Ohm,+/-5%,1/8W,G,SMD0402 | KOA SPEER ELECTRONICS, INC. | SG73P1ETTP1R0J | G | PWA BOM | In New BOM |
|  |  |  | 610154800-011-G | RES,1 Ohm,+/-5%,1/8W,G,SMD0402 | YAGEO CORPORATION COMPONENT | RC0402JR-7W1RL |  | PWA BOM | In New BOM |
|  |  |  | 610154800-012-G | RES,1 Ohm,+/-5%,1/8W,G,SMD0402 | WALSIN TECHNOLOGY CORPORATION | WF04P1R0 JTL |  | PWA BOM | In New BOM |
|  | R2060 | 1 | 610154800-017-G | RES,1 Ohm,+/-5%,1/8W,G,SMD0402 | KOA SPEER ELECTRONICS, INC. | SG73P1ETTP1R0J | G | PWA BOM | In Old BOM |
| ##### Change Revision |  |  |  |  |  |  |  |  |  |
| Sheet | REV OF BOM | CUSTOMER | CUSTOMER P/N | PWA PN | PWA DESCRIPTION | PWA REV | DATE | Remark |  |
| OOOOOOOOOOOOOOOOOOOOOOOOOOOOOOOOOOOOOOOOOOOOOOOOOOOOOOOOOOOOOOOOOOOOOOOOOOOOOOOOOOOOOOOOOO | OOOOOOOOOOOOOOOOOOOOOOOOOOOOOOOOOOOOOOOOOOOOOOOOOOOOOOOOOOOOOOOOOOOOOOOOOOOOOOOOOOOOOOOOOO | OOOOOOOOOOOOOOOOOOOOOOOOOOOOOOOOOOOOOOOOOOOOOOOOOOOOOOOOOOOOOOOOOOOOOOOOOOOOOOOOOOOOOOOOOO | OOOOOOOOOOOOOOOOOOOOOOOOOOOOOOOOOOOOOOOOOOOOOOOOOOOOOOOOOOOOOOOOOOOOOOOOOOOOOOOOOOOOOOOOOO | OOOOOOOOOOOOOOOOOOOOOOOOOOOOOOOOOOOOOOOOOOOOOOOOOOOOOOOOOOOOOOOOOOOOOOOOOOOOOOOOOOOOOOOOOO | OOOOOOOOOOOOOOOOOOOOOOOOOOOOOOOOOOOOOOOOOOOOOOOOOOOOOOOOOOOOOOOOOOOOOOOOOOOOOOOOOOOOOOOOOO | OOOOOOOOOOOOOOOOOOOOOOOOOOOOOOOOOOOOOOOOOOOOOOOOOOOOOOOOOOOOOOOOOOOOOOOOOOOOOOOOOOOOOOOOOO | OOOOOOOOOOOOOOOOOOOOOOOOOOOOOOOOOOOOOOOOOOOOOOOOOOOOOOOOOOOOOOOOOOOOOOOOOOOOOOOOOOOOOOOOOO | OOOOOOOOOOOOOOOOOOOOOOOOOOOOOOOOOOOOOOOOOOOOOOOOOOOOOOOOOOOOOOOOOOOOOOOOOOOOOOOOOOOOOOOOOO | OOOOOOOOOOOOOOOOOOOOOOOOOOOOOOOOOOOOOOOOOOOOOOOOOOOOOOOOOOOOOOOOOOOOOOOOOOOOOOOOOOOOOOOOOO |
| Second Source Change |  |  |  |  |  |  |  |  |  |
| Item | Location | Change Type | Foxconn P/N | Part Description | Manufacturer Full Name | Manufacturer P/N | RoHS | Sheet |  |
| 1 | C2268,C2269 |  | 62012UW00-015-G | CAP,6.8pF,+/-0.05pF,NPO(C0G),25V,G,SMD0402 | MURATA ELEC. NORTH AMERICA | GRM1555C1E6R8WA01D | G | PWA BOM |  |
|  |  | ADD | 62012UW00-012-G | CAP,6.8pF,+/-0.05pF,NPO(C0G),25V,G,SMD0402 | WALSIN TECHNOLOGY CORPORATION | 0402N6R8A250CT |  | PWA BOM |  |
| 2 | R875,R877,R879,R881,R883,R885,R887,R889,R891,R893,R895,R897,R899,R901,R903,R905,R907,R909,R911,R913,R915,R917,R919,R921 |  | 61015K700-017-G | RES,3.3 Ohm,+/-5%,1/2W,G,SMD1210 | KOA SPEER ELECTRONICS, INC. | RK73B2ETTD3R3J | G | PWA BOM |  |
|  |  | ADD | 61015K700-011-G | RES,3.3 Ohm,+/-5%,1/2W,G,SMD1210 | YAGEO CORPORATION COMPONENT | RC1210JR-073R3L |  | PWA BOM |  |
| 3 | R2060 |  | 610154800-017-G | RES,1 Ohm,+/-5%,1/8W,G,SMD0402 | KOA SPEER ELECTRONICS, INC. | SG73P1ETTP1R0J | G | PWA BOM |  |
|  |  | ADD | 610154800-011-G | RES,1 Ohm,+/-5%,1/8W,G,SMD0402 | YAGEO CORPORATION COMPONENT | RC0402JR-7W1RL |  | PWA BOM |  |
|  |  | ADD | 610154800-012-G | RES,1 Ohm,+/-5%,1/8W,G,SMD0402 | WALSIN TECHNOLOGY CORPORATION | WF04P1R0 JTL |  | PWA BOM |  |
| OOOOOOOOOOOOOOOOOOOOOOOOOOOOOOOOOOOOOOOOOOOOOOOOOOOOOOOOOOOOOOOOOOOOOOOOOOOOOOOOOOOOOOOOOO | OOOOOOOOOOOOOOOOOOOOOOOOOOOOOOOOOOOOOOOOOOOOOOOOOOOOOOOOOOOOOOOOOOOOOOOOOOOOOOOOOOOOOOOOOO | OOOOOOOOOOOOOOOOOOOOOOOOOOOOOOOOOOOOOOOOOOOOOOOOOOOOOOOOOOOOOOOOOOOOOOOOOOOOOOOOOOOOOOOOOO | OOOOOOOOOOOOOOOOOOOOOOOOOOOOOOOOOOOOOOOOOOOOOOOOOOOOOOOOOOOOOOOOOOOOOOOOOOOOOOOOOOOOOOOOOO | OOOOOOOOOOOOOOOOOOOOOOOOOOOOOOOOOOOOOOOOOOOOOOOOOOOOOOOOOOOOOOOOOOOOOOOOOOOOOOOOOOOOOOOOOO | OOOOOOOOOOOOOOOOOOOOOOOOOOOOOOOOOOOOOOOOOOOOOOOOOOOOOOOOOOOOOOOOOOOOOOOOOOOOOOOOOOOOOOOOOO | OOOOOOOOOOOOOOOOOOOOOOOOOOOOOOOOOOOOOOOOOOOOOOOOOOOOOOOOOOOOOOOOOOOOOOOOOOOOOOOOOOOOOOOOOO | OOOOOOOOOOOOOOOOOOOOOOOOOOOOOOOOOOOOOOOOOOOOOOOOOOOOOOOOOOOOOOOOOOOOOOOOOOOOOOOOOOOOOOOOOO | OOOOOOOOOOOOOOOOOOOOOOOOOOOOOOOOOOOOOOOOOOOOOOOOOOOOOOOOOOOOOOOOOOOOOOOOOOOOOOOOOOOOOOOOOO | OOOOOOOOOOOOOOOOOOOOOOOOOOOOOOOOOOOOOOOOOOOOOOOOOOOOOOOOOOOOOOOOOOOOOOOOOOOOOOOOOOOOOOOOOO |
| Master Materials Change |  |  |  |  |  |  |  |  |  |
| Item | Foxconn P/N | Orig._Usage | New_Usage | Part Description | Manufacturer Full Name | Manufacturer P/N | RoHS | Location | Sheet |
| 1 | 620101T02-015-G | 144 | 145 | CAP,100nF,+/-10%,X7R,16V,G,SMD0402 | MURATA ELEC. NORTH AMERICA | GRM155R71C104K | G | (+)C2272 | PWA BOM |
|  | 620101T00-012-G |  |  | CAP,100nF,+/-10%,X7R,16V,G,SMD0402 | WALSIN TECHNOLOGY CORPORATION | 0402B104K160CT |  |  | PWA BOM |
|  | 620101T00-026-G |  |  | CAP,100nF,+/-10%,X7R,16V,G,SMD0402 | SAMSUNG SEMICONDUCTOR | CL05B104KO5NNNC |  |  | PWA BOM |
|  | 620101T00-015-G |  |  | CAP,100nF,+/-10%,X7R,16V,G,SMD0402 | MURATA ELEC. NORTH AMERICA | GRM155R71C104KA88D |  |  | PWA BOM |
| 2 | 610107A00-017-G | 125 | 126 | RES,0 Ohm,+/-5%,1/16W,G,SMD0402 | KOA SPEER ELECTRONICS, INC. | RK73Z1ETTP | G | (+)R2158 | PWA BOM |
|  | 610107A00-012-G |  |  | RES,0 Ohm,+/-5%,1/16W,G,SMD0402 | WALSIN TECHNOLOGY CORPORATION | WR04X000PTL |  |  | PWA BOM |
|  | 610107A00-011-G |  |  | RES,0 Ohm,+/-5%,1/16W,G,SMD0402 | YAGEO CORPORATION COMPONENT | RC0402JR-070RL |  |  | PWA BOM |
|  | 610107A00-044-G |  |  | RES,0 Ohm,+/-5%,1/16W,G,SMD0402 | TA-I TECHNOLOGY CO., LTD | RM04JTN0 |  |  | PWA BOM |
|  | 610107A00-024-G |  |  | RES,0 Ohm,+/-5%,1/16W,G,SMD0402 | PANASONIC INDUSTRIAL CO.,LTD. | ERJ2GE0R00X |  |  | PWA BOM |
|  | 610107A00-029-G |  |  | RES,0 Ohm,+/-5%,1/16W,G,SMD0402 | VISHAY ENTER TECHNO LOGY.INC | CRCW04020000Z0ED |  |  | PWA BOM |
| 3 | 310101400-031-G | 2 | 3 | IC,Gate&Inverter,74LVC1G08GW,1.65~5.5V,G,SOT353-5,SMD | NXP SEMICONDUCTORS | 74LVC1G08GW | G | (+)U5 | PWA BOM |
|  | 310103J00-223-G |  |  | IC,Gate&Inverter,NL17SZ08DFT2G,1.65~5.5V,G,SOT353-5,SMD | ON SEMICONDUCTOR CORP | NL17SZ08DFT2G |  |  | PWA BOM |
|  | 31010J400-131-G |  |  | IC,Gate&Inverter,TC7SZ08FU,1.8~5.5V,G,SSOP-5,SMD | TOSHIBA ELECTRONICS ASIA LTD | TC7SZ08FU |  |  | PWA BOM |
| OOOOOOOOOOOOOOOOOOOOOOOOOOOOOOOOOOOOOOOOOOOOOOOOOOOOOOOOOOOOOOOOOOOOOOOOOOOOOOOOOOOOOOOOOO | OOOOOOOOOOOOOOOOOOOOOOOOOOOOOOOOOOOOOOOOOOOOOOOOOOOOOOOOOOOOOOOOOOOOOOOOOOOOOOOOOOOOOOOOOO | OOOOOOOOOOOOOOOOOOOOOOOOOOOOOOOOOOOOOOOOOOOOOOOOOOOOOOOOOOOOOOOOOOOOOOOOOOOOOOOOOOOOOOOOOO | OOOOOOOOOOOOOOOOOOOOOOOOOOOOOOOOOOOOOOOOOOOOOOOOOOOOOOOOOOOOOOOOOOOOOOOOOOOOOOOOOOOOOOOOOO | OOOOOOOOOOOOOOOOOOOOOOOOOOOOOOOOOOOOOOOOOOOOOOOOOOOOOOOOOOOOOOOOOOOOOOOOOOOOOOOOOOOOOOOOOO | OOOOOOOOOOOOOOOOOOOOOOOOOOOOOOOOOOOOOOOOOOOOOOOOOOOOOOOOOOOOOOOOOOOOOOOOOOOOOOOOOOOOOOOOOO | OOOOOOOOOOOOOOOOOOOOOOOOOOOOOOOOOOOOOOOOOOOOOOOOOOOOOOOOOOOOOOOOOOOOOOOOOOOOOOOOOOOOOOOOOO | OOOOOOOOOOOOOOOOOOOOOOOOOOOOOOOOOOOOOOOOOOOOOOOOOOOOOOOOOOOOOOOOOOOOOOOOOOOOOOOOOOOOOOOOOO | OOOOOOOOOOOOOOOOOOOOOOOOOOOOOOOOOOOOOOOOOOOOOOOOOOOOOOOOOOOOOOOOOOOOOOOOOOOOOOOOOOOOOOOOOO |  |
| TLA Parts Change |  |  |  |  |  |  |  |  |  |
| Item | Foxconn P/N | Qty | Part Description | Manufacturer Full Name | Manufacturer P/N | RoHS | Location | Remark |  |
| BOM Change List Date:Fri Sep 29 10:31:02 GMT+08:00 2017 |  |  |  |  |  |  |  |  |  |
| New BOM file : E:\barreleye g2\0928\Barreleye-G2_Tri-mode Expander-DVT-X01-BOM-X07-20170928.xls |  |  |  |  |  |  |  |  |  |
| Old BOM file : E:\barreleye g2\0928\EXPANDER0922.xls |  |  |  |  |  |  |  |  |  |
| ##### Add Parts |  |  |  |  |  |  |  |  |  |
| Item | Location | Qty | Foxconn P/N | Part Description | Manufacturer Full Name | Manufacturer P/N | RoHS | Sheet |  |
| ##### Remove Parts |  |  |  |  |  |  |  |  |  |
| Item | Location | Qty | Foxconn P/N | Part Description | Manufacturer Full Name | Manufacturer P/N | RoHS | Sheet |  |
| ##### Change Parts |  |  |  |  |  |  |  |  |  |
| Item | Location | Qty | Foxconn P/N | Part Description | Manufacturer Full Name | Manufacturer P/N | RoHS | Sheet | Remark |
| 1 | J_PCIE_OUT1,J_PCIE_IN1,J_PCIE_OUT2,J_PCIE_IN2,J_PCIE_OUT3,J_PCIE_OUT4,J4,J_PCIE_OUT5,J5,J_PCIE_OUT6,J6,J_PCIE_OUT7 | 12 | 340718A00-245-G | CONN,SAS,V/T,0.6mm,30u,G,SMD-74 | AMPHENOL SHANGHAI CORP. | U10-B074-250T | G | PWA BOM | In New BOM |
|  | J_PCIE_OUT1,J_PCIE_IN1,J_PCIE_OUT2,J_PCIE_IN2,J_PCIE_OUT3,J_PCIE_OUT4,J4,J_PCIE_OUT5,J5,J_PCIE_OUT6,J6,J_PCIE_OUT7 | 12 | 340718900-245-G | CONN,SAS,V/T,0.6mm,30u,G,SMD-74 | AMPHENOL SHANGHAI CORP. | U10-B074-260T | G | PWA BOM | In Old BOM |
| ##### Change Revision |  |  |  |  |  |  |  |  |  |
| Sheet | REV OF BOM | CUSTOMER | CUSTOMER P/N | PWA PN | PWA DESCRIPTION | PWA REV | DATE | Remark |  |
| OOOOOOOOOOOOOOOOOOOOOOOOOOOOOOOOOOOOOOOOOOOOOOOOOOOOOOOOOOOOOOOOOOOOOOOOOOOOOOOOOOOOOOOOOO | OOOOOOOOOOOOOOOOOOOOOOOOOOOOOOOOOOOOOOOOOOOOOOOOOOOOOOOOOOOOOOOOOOOOOOOOOOOOOOOOOOOOOOOOOO | OOOOOOOOOOOOOOOOOOOOOOOOOOOOOOOOOOOOOOOOOOOOOOOOOOOOOOOOOOOOOOOOOOOOOOOOOOOOOOOOOOOOOOOOOO | OOOOOOOOOOOOOOOOOOOOOOOOOOOOOOOOOOOOOOOOOOOOOOOOOOOOOOOOOOOOOOOOOOOOOOOOOOOOOOOOOOOOOOOOOO | OOOOOOOOOOOOOOOOOOOOOOOOOOOOOOOOOOOOOOOOOOOOOOOOOOOOOOOOOOOOOOOOOOOOOOOOOOOOOOOOOOOOOOOOOO | OOOOOOOOOOOOOOOOOOOOOOOOOOOOOOOOOOOOOOOOOOOOOOOOOOOOOOOOOOOOOOOOOOOOOOOOOOOOOOOOOOOOOOOOOO | OOOOOOOOOOOOOOOOOOOOOOOOOOOOOOOOOOOOOOOOOOOOOOOOOOOOOOOOOOOOOOOOOOOOOOOOOOOOOOOOOOOOOOOOOO | OOOOOOOOOOOOOOOOOOOOOOOOOOOOOOOOOOOOOOOOOOOOOOOOOOOOOOOOOOOOOOOOOOOOOOOOOOOOOOOOOOOOOOOOOO | OOOOOOOOOOOOOOOOOOOOOOOOOOOOOOOOOOOOOOOOOOOOOOOOOOOOOOOOOOOOOOOOOOOOOOOOOOOOOOOOOOOOOOOOOO | OOOOOOOOOOOOOOOOOOOOOOOOOOOOOOOOOOOOOOOOOOOOOOOOOOOOOOOOOOOOOOOOOOOOOOOOOOOOOOOOOOOOOOOOOO |
| Second Source Change |  |  |  |  |  |  |  |  |  |
| Item | Location | Change Type | Foxconn P/N | Part Description | Manufacturer Full Name | Manufacturer P/N | RoHS | Sheet |  |
| OOOOOOOOOOOOOOOOOOOOOOOOOOOOOOOOOOOOOOOOOOOOOOOOOOOOOOOOOOOOOOOOOOOOOOOOOOOOOOOOOOOOOOOOOO | OOOOOOOOOOOOOOOOOOOOOOOOOOOOOOOOOOOOOOOOOOOOOOOOOOOOOOOOOOOOOOOOOOOOOOOOOOOOOOOOOOOOOOOOOO | OOOOOOOOOOOOOOOOOOOOOOOOOOOOOOOOOOOOOOOOOOOOOOOOOOOOOOOOOOOOOOOOOOOOOOOOOOOOOOOOOOOOOOOOOO | OOOOOOOOOOOOOOOOOOOOOOOOOOOOOOOOOOOOOOOOOOOOOOOOOOOOOOOOOOOOOOOOOOOOOOOOOOOOOOOOOOOOOOOOOO | OOOOOOOOOOOOOOOOOOOOOOOOOOOOOOOOOOOOOOOOOOOOOOOOOOOOOOOOOOOOOOOOOOOOOOOOOOOOOOOOOOOOOOOOOO | OOOOOOOOOOOOOOOOOOOOOOOOOOOOOOOOOOOOOOOOOOOOOOOOOOOOOOOOOOOOOOOOOOOOOOOOOOOOOOOOOOOOOOOOOO | OOOOOOOOOOOOOOOOOOOOOOOOOOOOOOOOOOOOOOOOOOOOOOOOOOOOOOOOOOOOOOOOOOOOOOOOOOOOOOOOOOOOOOOOOO | OOOOOOOOOOOOOOOOOOOOOOOOOOOOOOOOOOOOOOOOOOOOOOOOOOOOOOOOOOOOOOOOOOOOOOOOOOOOOOOOOOOOOOOOOO | OOOOOOOOOOOOOOOOOOOOOOOOOOOOOOOOOOOOOOOOOOOOOOOOOOOOOOOOOOOOOOOOOOOOOOOOOOOOOOOOOOOOOOOOOO | OOOOOOOOOOOOOOOOOOOOOOOOOOOOOOOOOOOOOOOOOOOOOOOOOOOOOOOOOOOOOOOOOOOOOOOOOOOOOOOOOOOOOOOOOO |
| Master Materials Change |  |  |  |  |  |  |  |  |  |
| Item | Foxconn P/N | Orig._Usage | New_Usage | Part Description | Manufacturer Full Name | Manufacturer P/N | RoHS | Location | Sheet |
| 1 | 340718A00-245-G | 0 | 12 | CONN,SAS,V/T,0.6mm,30u,G,SMD-74 | AMPHENOL SHANGHAI CORP. | U10-B074-250T | G | (+)J_PCIE_OUT1,J_PCIE_IN1,J_PCIE_OUT2,J_PCIE_IN2,J_PCIE_OUT3,J_PCIE_OUT4,J4,J_PCIE_OUT5,J5,J_PCIE_OUT6,J6,J_PCIE_OUT7 | PWA BOM |
| 2 | 340718900-245-G | 12 | 0 | CONN,SAS,V/T,0.6mm,30u,G,SMD-74 | AMPHENOL SHANGHAI CORP. | U10-B074-260T | G | (-)J_PCIE_OUT1,J_PCIE_IN1,J_PCIE_OUT2,J_PCIE_IN2,J_PCIE_OUT3,J_PCIE_OUT4,J4,J_PCIE_OUT5,J5,J_PCIE_OUT6,J6,J_PCIE_OUT7 | PWA BOM |
| OOOOOOOOOOOOOOOOOOOOOOOOOOOOOOOOOOOOOOOOOOOOOOOOOOOOOOOOOOOOOOOOOOOOOOOOOOOOOOOOOOOOOOOOOO | OOOOOOOOOOOOOOOOOOOOOOOOOOOOOOOOOOOOOOOOOOOOOOOOOOOOOOOOOOOOOOOOOOOOOOOOOOOOOOOOOOOOOOOOOO | OOOOOOOOOOOOOOOOOOOOOOOOOOOOOOOOOOOOOOOOOOOOOOOOOOOOOOOOOOOOOOOOOOOOOOOOOOOOOOOOOOOOOOOOOO | OOOOOOOOOOOOOOOOOOOOOOOOOOOOOOOOOOOOOOOOOOOOOOOOOOOOOOOOOOOOOOOOOOOOOOOOOOOOOOOOOOOOOOOOOO | OOOOOOOOOOOOOOOOOOOOOOOOOOOOOOOOOOOOOOOOOOOOOOOOOOOOOOOOOOOOOOOOOOOOOOOOOOOOOOOOOOOOOOOOOO | OOOOOOOOOOOOOOOOOOOOOOOOOOOOOOOOOOOOOOOOOOOOOOOOOOOOOOOOOOOOOOOOOOOOOOOOOOOOOOOOOOOOOOOOOO | OOOOOOOOOOOOOOOOOOOOOOOOOOOOOOOOOOOOOOOOOOOOOOOOOOOOOOOOOOOOOOOOOOOOOOOOOOOOOOOOOOOOOOOOOO | OOOOOOOOOOOOOOOOOOOOOOOOOOOOOOOOOOOOOOOOOOOOOOOOOOOOOOOOOOOOOOOOOOOOOOOOOOOOOOOOOOOOOOOOOO | OOOOOOOOOOOOOOOOOOOOOOOOOOOOOOOOOOOOOOOOOOOOOOOOOOOOOOOOOOOOOOOOOOOOOOOOOOOOOOOOOOOOOOOOOO |  |
| TLA Parts Change |  |  |  |  |  |  |  |  |  |
| Item | Foxconn P/N | Qty | Part Description | Manufacturer Full Name | Manufacturer P/N | RoHS | Location | Remark |  |
| BOM Change List Date:Tue Oct 17 14:18:13 GMT+08:00 2017 |  |  |  |  |  |  |  |  |  |
| New BOM file : E:\barreleye g2\1016\EXPANDER 1017.xls |  |  |  |  |  |  |  |  |  |
| Old BOM file : E:\barreleye g2\1016\EXPANDER 0929.xls |  |  |  |  |  |  |  |  |  |
| ##### Add Parts |  |  |  |  |  |  |  |  |  |
| Item | Location | Qty | Foxconn P/N | Part Description | Manufacturer Full Name | Manufacturer P/N | RoHS | Sheet |  |
| ##### Remove Parts |  |  |  |  |  |  |  |  |  |
| Item | Location | Qty | Foxconn P/N | Part Description | Manufacturer Full Name | Manufacturer P/N | RoHS | Sheet |  |
| ##### Change Parts |  |  |  |  |  |  |  |  |  |
| Item | Location | Qty | Foxconn P/N | Part Description | Manufacturer Full Name | Manufacturer P/N | RoHS | Sheet | Remark |
| 1 | PCB | 1 | 0101FGB00-000-G | PCB,Zaius-Tri-mode Expander DVT-X01,Blu,10L,9.134*5.118,G | NON DEDICATED | 0101FGB00-000-G | G | PWA BOM | In New BOM |
|  | PCB | 1 | PCB | PCB | PCB | PCB | G | PWA BOM | In Old BOM |
| ##### Change Revision |  |  |  |  |  |  |  |  |  |
| Sheet | REV OF BOM | CUSTOMER | CUSTOMER P/N | PWA PN | PWA DESCRIPTION | PWA REV | DATE | Remark |  |
| OOOOOOOOOOOOOOOOOOOOOOOOOOOOOOOOOOOOOOOOOOOOOOOOOOOOOOOOOOOOOOOOOOOOOOOOOOOOOOOOOOOOOOOOOO | OOOOOOOOOOOOOOOOOOOOOOOOOOOOOOOOOOOOOOOOOOOOOOOOOOOOOOOOOOOOOOOOOOOOOOOOOOOOOOOOOOOOOOOOOO | OOOOOOOOOOOOOOOOOOOOOOOOOOOOOOOOOOOOOOOOOOOOOOOOOOOOOOOOOOOOOOOOOOOOOOOOOOOOOOOOOOOOOOOOOO | OOOOOOOOOOOOOOOOOOOOOOOOOOOOOOOOOOOOOOOOOOOOOOOOOOOOOOOOOOOOOOOOOOOOOOOOOOOOOOOOOOOOOOOOOO | OOOOOOOOOOOOOOOOOOOOOOOOOOOOOOOOOOOOOOOOOOOOOOOOOOOOOOOOOOOOOOOOOOOOOOOOOOOOOOOOOOOOOOOOOO | OOOOOOOOOOOOOOOOOOOOOOOOOOOOOOOOOOOOOOOOOOOOOOOOOOOOOOOOOOOOOOOOOOOOOOOOOOOOOOOOOOOOOOOOOO | OOOOOOOOOOOOOOOOOOOOOOOOOOOOOOOOOOOOOOOOOOOOOOOOOOOOOOOOOOOOOOOOOOOOOOOOOOOOOOOOOOOOOOOOOO | OOOOOOOOOOOOOOOOOOOOOOOOOOOOOOOOOOOOOOOOOOOOOOOOOOOOOOOOOOOOOOOOOOOOOOOOOOOOOOOOOOOOOOOOOO | OOOOOOOOOOOOOOOOOOOOOOOOOOOOOOOOOOOOOOOOOOOOOOOOOOOOOOOOOOOOOOOOOOOOOOOOOOOOOOOOOOOOOOOOOO | OOOOOOOOOOOOOOOOOOOOOOOOOOOOOOOOOOOOOOOOOOOOOOOOOOOOOOOOOOOOOOOOOOOOOOOOOOOOOOOOOOOOOOOOOO |
| Second Source Change |  |  |  |  |  |  |  |  |  |
| Item | Location | Change Type | Foxconn P/N | Part Description | Manufacturer Full Name | Manufacturer P/N | RoHS | Sheet |  |
| OOOOOOOOOOOOOOOOOOOOOOOOOOOOOOOOOOOOOOOOOOOOOOOOOOOOOOOOOOOOOOOOOOOOOOOOOOOOOOOOOOOOOOOOOO | OOOOOOOOOOOOOOOOOOOOOOOOOOOOOOOOOOOOOOOOOOOOOOOOOOOOOOOOOOOOOOOOOOOOOOOOOOOOOOOOOOOOOOOOOO | OOOOOOOOOOOOOOOOOOOOOOOOOOOOOOOOOOOOOOOOOOOOOOOOOOOOOOOOOOOOOOOOOOOOOOOOOOOOOOOOOOOOOOOOOO | OOOOOOOOOOOOOOOOOOOOOOOOOOOOOOOOOOOOOOOOOOOOOOOOOOOOOOOOOOOOOOOOOOOOOOOOOOOOOOOOOOOOOOOOOO | OOOOOOOOOOOOOOOOOOOOOOOOOOOOOOOOOOOOOOOOOOOOOOOOOOOOOOOOOOOOOOOOOOOOOOOOOOOOOOOOOOOOOOOOOO | OOOOOOOOOOOOOOOOOOOOOOOOOOOOOOOOOOOOOOOOOOOOOOOOOOOOOOOOOOOOOOOOOOOOOOOOOOOOOOOOOOOOOOOOOO | OOOOOOOOOOOOOOOOOOOOOOOOOOOOOOOOOOOOOOOOOOOOOOOOOOOOOOOOOOOOOOOOOOOOOOOOOOOOOOOOOOOOOOOOOO | OOOOOOOOOOOOOOOOOOOOOOOOOOOOOOOOOOOOOOOOOOOOOOOOOOOOOOOOOOOOOOOOOOOOOOOOOOOOOOOOOOOOOOOOOO | OOOOOOOOOOOOOOOOOOOOOOOOOOOOOOOOOOOOOOOOOOOOOOOOOOOOOOOOOOOOOOOOOOOOOOOOOOOOOOOOOOOOOOOOOO | OOOOOOOOOOOOOOOOOOOOOOOOOOOOOOOOOOOOOOOOOOOOOOOOOOOOOOOOOOOOOOOOOOOOOOOOOOOOOOOOOOOOOOOOOO |
| Master Materials Change |  |  |  |  |  |  |  |  |  |
| Item | Foxconn P/N | Orig._Usage | New_Usage | Part Description | Manufacturer Full Name | Manufacturer P/N | RoHS | Location | Sheet |
| 1 | 0101FGB00-000-G | 0 | 1 | PCB,Zaius-Tri-mode Expander DVT-X01,Blu,10L,9.134*5.118,G | NON DEDICATED | 0101FGB00-000-G | G | (+)PCB | PWA BOM |
| 2 | PCB | 1 | 0 | PCB | PCB | PCB | G | (-)PCB | PWA BOM |
| OOOOOOOOOOOOOOOOOOOOOOOOOOOOOOOOOOOOOOOOOOOOOOOOOOOOOOOOOOOOOOOOOOOOOOOOOOOOOOOOOOOOOOOOOO | OOOOOOOOOOOOOOOOOOOOOOOOOOOOOOOOOOOOOOOOOOOOOOOOOOOOOOOOOOOOOOOOOOOOOOOOOOOOOOOOOOOOOOOOOO | OOOOOOOOOOOOOOOOOOOOOOOOOOOOOOOOOOOOOOOOOOOOOOOOOOOOOOOOOOOOOOOOOOOOOOOOOOOOOOOOOOOOOOOOOO | OOOOOOOOOOOOOOOOOOOOOOOOOOOOOOOOOOOOOOOOOOOOOOOOOOOOOOOOOOOOOOOOOOOOOOOOOOOOOOOOOOOOOOOOOO | OOOOOOOOOOOOOOOOOOOOOOOOOOOOOOOOOOOOOOOOOOOOOOOOOOOOOOOOOOOOOOOOOOOOOOOOOOOOOOOOOOOOOOOOOO | OOOOOOOOOOOOOOOOOOOOOOOOOOOOOOOOOOOOOOOOOOOOOOOOOOOOOOOOOOOOOOOOOOOOOOOOOOOOOOOOOOOOOOOOOO | OOOOOOOOOOOOOOOOOOOOOOOOOOOOOOOOOOOOOOOOOOOOOOOOOOOOOOOOOOOOOOOOOOOOOOOOOOOOOOOOOOOOOOOOOO | OOOOOOOOOOOOOOOOOOOOOOOOOOOOOOOOOOOOOOOOOOOOOOOOOOOOOOOOOOOOOOOOOOOOOOOOOOOOOOOOOOOOOOOOOO | OOOOOOOOOOOOOOOOOOOOOOOOOOOOOOOOOOOOOOOOOOOOOOOOOOOOOOOOOOOOOOOOOOOOOOOOOOOOOOOOOOOOOOOOOO |  |
| TLA Parts Change |  |  |  |  |  |  |  |  |  |
| Item | Foxconn P/N | Qty | Part Description | Manufacturer Full Name | Manufacturer P/N | RoHS | Location | Remark |  |
| BOM Change List Date:Tue Oct 24 15:30:12 CST 2017 |  |  |  |  |  |  |  |  |  |
| New BOM file : E:\barreleye g2\1024\EXPANDER 1024.xls |  |  |  |  |  |  |  |  |  |
| Old BOM file : E:\barreleye g2\1024\EXPANDER 1017.xls |  |  |  |  |  |  |  |  |  |
| ##### Add Parts |  |  |  |  |  |  |  |  |  |
| Item | Location | Qty | Foxconn P/N | Part Description | Manufacturer Full Name | Manufacturer P/N | RoHS | Sheet |  |
| 1 | R1544 | 1 | 61010G500-017-G | RES,10KOhm,+/-1%,1/16W,G,SMD0402 | KOA SPEER ELECTRONICS, INC. | RK73H1ETTP1002F | G | PWA BOM |  |
|  |  |  | 61010G500-012-G | RES,10KOhm,+/-1%,1/16W,G,SMD0402 | WALSIN TECHNOLOGY CORPORATION | WR04X1002FTL | G | PWA BOM |  |
|  |  |  | 61010G500-011-G | RES,10KOhm,+/-1%,1/16W,G,SMD0402 | YAGEO CORPORATION COMPONENT | RC0402FR-0710KL | G | PWA BOM |  |
|  |  |  | 61010G500-044-G | RES,10KOhm,+/-1%,1/16W,G,SMD0402 | TA-I TECHNOLOGY CO., LTD. | RM04FTN1002 | G | PWA BOM |  |
|  |  |  | 61010G500-029-G | RES,10KOhm,+/-1%,1/16W,G,SMD0402 | VISHAY ENTER TECHNO LOGY.INC | CRCW040210K0FKED | G | PWA BOM |  |
|  |  |  | 61010G500-024-G | RES,10KOhm,+/-1%,1/16W,G,SMD0402 | PANASONIC INDUSTRIAL CO.,LTD. | ERJ2RKF1002X | G | PWA BOM |  |
| ##### Remove Parts |  |  |  |  |  |  |  |  |  |
| Item | Location | Qty | Foxconn P/N | Part Description | Manufacturer Full Name | Manufacturer P/N | RoHS | Sheet |  |
| 1 | R75,R76,R77 | 3 | 61010JY00-017-G | RES,220 Ohm,+/-5%,1/16W,G,SMD0402 | KOA SPEER ELECTRONICS, INC. | RK73B1ETTP221J | G | PWA BOM |  |
|  |  |  | 61010JY00-012-G | RES,220 Ohm,+/-5%,1/16W,G,SMD0402 | WALSIN TECHNOLOGY CORPORATION | WR04X221JTL | G | PWA BOM |  |
|  |  |  | 61010JY00-011-G | RES,220 Ohm,+/-5%,1/16W,G,SMD0402 | YAGEO CORPORATION COMPONENT | RC0402JR-07220RL | G | PWA BOM |  |
|  |  |  | 61010JY00-044-G | RES,220 Ohm,+/-5%,1/16W,G,SMD0402 | TA-I TECHNOLOGY CO., LTD. | RM04JTN221 | G | PWA BOM |  |
| ##### Change Parts |  |  |  |  |  |  |  |  |  |
| Item | Location | Qty | Foxconn P/N | Part Description | Manufacturer Full Name | Manufacturer P/N | RoHS | Sheet | Remark |
| 1 | J_PCIE_OUT1,J_PCIE_IN1,J_PCIE_OUT2,J_PCIE_IN2,J_PCIE_OUT3,J_PCIE_OUT4,J4,J_PCIE_OUT5,J5,J_PCIE_OUT6,J6,J_PCIE_OUT7 | 12 | 340718A00-245-G | CONN,SAS,V/T,0.6mm,30u,G,SMD-74 | AMPHENOL SHANGHAI CORP. | U10-B074-250T | G | PWA BOM | In New BOM |
|  |  |  | U10-B274-250T | CONN,SAS,V/T,0.6mm,30u,G,SMD-74 | AMPHENOL SHANGHAI CORP. | U10-B274-250T | G | PWA BOM | In New BOM |
|  | J_PCIE_OUT1,J_PCIE_IN1,J_PCIE_OUT2,J_PCIE_IN2,J_PCIE_OUT3,J_PCIE_OUT4,J4,J_PCIE_OUT5,J5,J_PCIE_OUT6,J6,J_PCIE_OUT7 | 12 | 340718A00-245-G | CONN,SAS,V/T,0.6mm,30u,G,SMD-74 | AMPHENOL SHANGHAI CORP. | U10-B074-250T | G | PWA BOM | In Old BOM |
| ##### Change Revision |  |  |  |  |  |  |  |  |  |
| Sheet | REV OF BOM | CUSTOMER | CUSTOMER P/N | PWA PN | PWA DESCRIPTION | PWA REV | DATE | Remark |  |
| OOOOOOOOOOOOOOOOOOOOOOOOOOOOOOOOOOOOOOOOOOOOOOOOOOOOOOOOOOOOOOOOOOOOOOOOOOOOOOOOOOOOOOOOOO | OOOOOOOOOOOOOOOOOOOOOOOOOOOOOOOOOOOOOOOOOOOOOOOOOOOOOOOOOOOOOOOOOOOOOOOOOOOOOOOOOOOOOOOOOO | OOOOOOOOOOOOOOOOOOOOOOOOOOOOOOOOOOOOOOOOOOOOOOOOOOOOOOOOOOOOOOOOOOOOOOOOOOOOOOOOOOOOOOOOOO | OOOOOOOOOOOOOOOOOOOOOOOOOOOOOOOOOOOOOOOOOOOOOOOOOOOOOOOOOOOOOOOOOOOOOOOOOOOOOOOOOOOOOOOOOO | OOOOOOOOOOOOOOOOOOOOOOOOOOOOOOOOOOOOOOOOOOOOOOOOOOOOOOOOOOOOOOOOOOOOOOOOOOOOOOOOOOOOOOOOOO | OOOOOOOOOOOOOOOOOOOOOOOOOOOOOOOOOOOOOOOOOOOOOOOOOOOOOOOOOOOOOOOOOOOOOOOOOOOOOOOOOOOOOOOOOO | OOOOOOOOOOOOOOOOOOOOOOOOOOOOOOOOOOOOOOOOOOOOOOOOOOOOOOOOOOOOOOOOOOOOOOOOOOOOOOOOOOOOOOOOOO | OOOOOOOOOOOOOOOOOOOOOOOOOOOOOOOOOOOOOOOOOOOOOOOOOOOOOOOOOOOOOOOOOOOOOOOOOOOOOOOOOOOOOOOOOO | OOOOOOOOOOOOOOOOOOOOOOOOOOOOOOOOOOOOOOOOOOOOOOOOOOOOOOOOOOOOOOOOOOOOOOOOOOOOOOOOOOOOOOOOOO | OOOOOOOOOOOOOOOOOOOOOOOOOOOOOOOOOOOOOOOOOOOOOOOOOOOOOOOOOOOOOOOOOOOOOOOOOOOOOOOOOOOOOOOOOO |
| Second Source Change |  |  |  |  |  |  |  |  |  |
| Item | Location | Change Type | Foxconn P/N | Part Description | Manufacturer Full Name | Manufacturer P/N | RoHS | Sheet |  |
| 1 | J_PCIE_OUT1,J_PCIE_IN1,J_PCIE_OUT2,J_PCIE_IN2,J_PCIE_OUT3,J_PCIE_OUT4,J4,J_PCIE_OUT5,J5,J_PCIE_OUT6,J6,J_PCIE_OUT7 |  | 340718A00-245-G | CONN,SAS,V/T,0.6mm,30u,G,SMD-74 | AMPHENOL SHANGHAI CORP. | U10-B074-250T | G | PWA BOM |  |
|  |  | ADD | U10-B274-250T | CONN,SAS,V/T,0.6mm,30u,G,SMD-74 | AMPHENOL SHANGHAI CORP. | U10-B274-250T | G | PWA BOM |  |
| OOOOOOOOOOOOOOOOOOOOOOOOOOOOOOOOOOOOOOOOOOOOOOOOOOOOOOOOOOOOOOOOOOOOOOOOOOOOOOOOOOOOOOOOOO | OOOOOOOOOOOOOOOOOOOOOOOOOOOOOOOOOOOOOOOOOOOOOOOOOOOOOOOOOOOOOOOOOOOOOOOOOOOOOOOOOOOOOOOOOO | OOOOOOOOOOOOOOOOOOOOOOOOOOOOOOOOOOOOOOOOOOOOOOOOOOOOOOOOOOOOOOOOOOOOOOOOOOOOOOOOOOOOOOOOOO | OOOOOOOOOOOOOOOOOOOOOOOOOOOOOOOOOOOOOOOOOOOOOOOOOOOOOOOOOOOOOOOOOOOOOOOOOOOOOOOOOOOOOOOOOO | OOOOOOOOOOOOOOOOOOOOOOOOOOOOOOOOOOOOOOOOOOOOOOOOOOOOOOOOOOOOOOOOOOOOOOOOOOOOOOOOOOOOOOOOOO | OOOOOOOOOOOOOOOOOOOOOOOOOOOOOOOOOOOOOOOOOOOOOOOOOOOOOOOOOOOOOOOOOOOOOOOOOOOOOOOOOOOOOOOOOO | OOOOOOOOOOOOOOOOOOOOOOOOOOOOOOOOOOOOOOOOOOOOOOOOOOOOOOOOOOOOOOOOOOOOOOOOOOOOOOOOOOOOOOOOOO | OOOOOOOOOOOOOOOOOOOOOOOOOOOOOOOOOOOOOOOOOOOOOOOOOOOOOOOOOOOOOOOOOOOOOOOOOOOOOOOOOOOOOOOOOO | OOOOOOOOOOOOOOOOOOOOOOOOOOOOOOOOOOOOOOOOOOOOOOOOOOOOOOOOOOOOOOOOOOOOOOOOOOOOOOOOOOOOOOOOOO | OOOOOOOOOOOOOOOOOOOOOOOOOOOOOOOOOOOOOOOOOOOOOOOOOOOOOOOOOOOOOOOOOOOOOOOOOOOOOOOOOOOOOOOOOO |
| Master Materials Change |  |  |  |  |  |  |  |  |  |
| Item | Foxconn P/N | Orig._Usage | New_Usage | Part Description | Manufacturer Full Name | Manufacturer P/N | RoHS | Location | Sheet |
| 1 | 61010G500-017-G | 61 | 62 | RES,10KOhm,+/-1%,1/16W,G,SMD0402 | KOA SPEER ELECTRONICS, INC. | RK73H1ETTP1002F | G | (+)R1544 | PWA BOM |
|  | 61010G500-012-G |  |  | RES,10KOhm,+/-1%,1/16W,G,SMD0402 | WALSIN TECHNOLOGY CORPORATION | WR04X1002FTL |  |  | PWA BOM |
|  | 61010G500-011-G |  |  | RES,10KOhm,+/-1%,1/16W,G,SMD0402 | YAGEO CORPORATION COMPONENT | RC0402FR-0710KL |  |  | PWA BOM |
|  | 61010G500-044-G |  |  | RES,10KOhm,+/-1%,1/16W,G,SMD0402 | TA-I TECHNOLOGY CO., LTD. | RM04FTN1002 |  |  | PWA BOM |
|  | 61010G500-029-G |  |  | RES,10KOhm,+/-1%,1/16W,G,SMD0402 | VISHAY ENTER TECHNO LOGY.INC | CRCW040210K0FKED |  |  | PWA BOM |
|  | 61010G500-024-G |  |  | RES,10KOhm,+/-1%,1/16W,G,SMD0402 | PANASONIC INDUSTRIAL CO.,LTD. | ERJ2RKF1002X |  |  | PWA BOM |
| 2 | 61010JY00-017-G | 8 | 5 | RES,220 Ohm,+/-5%,1/16W,G,SMD0402 | KOA SPEER ELECTRONICS, INC. | RK73B1ETTP221J | G | (-)R75,R76,R77 | PWA BOM |
|  | 61010JY00-012-G |  |  | RES,220 Ohm,+/-5%,1/16W,G,SMD0402 | WALSIN TECHNOLOGY CORPORATION | WR04X221JTL |  |  | PWA BOM |
|  | 61010JY00-011-G |  |  | RES,220 Ohm,+/-5%,1/16W,G,SMD0402 | YAGEO CORPORATION COMPONENT | RC0402JR-07220RL |  |  | PWA BOM |
|  | 61010JY00-044-G |  |  | RES,220 Ohm,+/-5%,1/16W,G,SMD0402 | TA-I TECHNOLOGY CO., LTD. | RM04JTN221 |  |  | PWA BOM |
| OOOOOOOOOOOOOOOOOOOOOOOOOOOOOOOOOOOOOOOOOOOOOOOOOOOOOOOOOOOOOOOOOOOOOOOOOOOOOOOOOOOOOOOOOO | OOOOOOOOOOOOOOOOOOOOOOOOOOOOOOOOOOOOOOOOOOOOOOOOOOOOOOOOOOOOOOOOOOOOOOOOOOOOOOOOOOOOOOOOOO | OOOOOOOOOOOOOOOOOOOOOOOOOOOOOOOOOOOOOOOOOOOOOOOOOOOOOOOOOOOOOOOOOOOOOOOOOOOOOOOOOOOOOOOOOO | OOOOOOOOOOOOOOOOOOOOOOOOOOOOOOOOOOOOOOOOOOOOOOOOOOOOOOOOOOOOOOOOOOOOOOOOOOOOOOOOOOOOOOOOOO | OOOOOOOOOOOOOOOOOOOOOOOOOOOOOOOOOOOOOOOOOOOOOOOOOOOOOOOOOOOOOOOOOOOOOOOOOOOOOOOOOOOOOOOOOO | OOOOOOOOOOOOOOOOOOOOOOOOOOOOOOOOOOOOOOOOOOOOOOOOOOOOOOOOOOOOOOOOOOOOOOOOOOOOOOOOOOOOOOOOOO | OOOOOOOOOOOOOOOOOOOOOOOOOOOOOOOOOOOOOOOOOOOOOOOOOOOOOOOOOOOOOOOOOOOOOOOOOOOOOOOOOOOOOOOOOO | OOOOOOOOOOOOOOOOOOOOOOOOOOOOOOOOOOOOOOOOOOOOOOOOOOOOOOOOOOOOOOOOOOOOOOOOOOOOOOOOOOOOOOOOOO | OOOOOOOOOOOOOOOOOOOOOOOOOOOOOOOOOOOOOOOOOOOOOOOOOOOOOOOOOOOOOOOOOOOOOOOOOOOOOOOOOOOOOOOOOO | OOOOOOOOOOOOOOOOOOOOOOOOOOOOOOOOOOOOOOOOOOOOOOOOOOOOOOOOOOOOOOOOOOOOOOOOOOOOOOOOOOOOOOOOOO |
| TLA Parts Change |  |  |  |  |  |  |  |  |  |
| Item | Foxconn P/N | Qty | Part Description | Manufacturer Full Name | Manufacturer P/N | RoHS | Location | Remark | BOM |
| BOM Change List Date:Fri Nov 03 14:54:47 GMT+08:00 2017 |  |  |  |  |  |  |  |  |  |
| New BOM file : E:\barreleye g2\1103\foxbis\EXPANDER 1103.xls |  |  |  |  |  |  |  |  |  |
| Old BOM file : E:\barreleye g2\1103\foxbis\EXPANDER 1024.xls |  |  |  |  |  |  |  |  |  |
| ##### Add Parts |  |  |  |  |  |  |  |  |  |
| Item | Location | Qty | Foxconn P/N | Part Description | Manufacturer Full Name | Manufacturer P/N | RoHS | Sheet |  |
| ##### Remove Parts |  |  |  |  |  |  |  |  |  |
| Item | Location | Qty | Foxconn P/N | Part Description | Manufacturer Full Name | Manufacturer P/N | RoHS | Sheet |  |
| ##### Change Parts |  |  |  |  |  |  |  |  |  |
| Item | Location | Qty | Foxconn P/N | Part Description | Manufacturer Full Name | Manufacturer P/N | RoHS | Sheet | Remark |
| 1 | L24 | 1 | 720101L00-015-G | FB,600 Ohm@100MHz,+/-25%,200mA,500mOhm,G,SMD0603 | MURATA ELEC. NORTH AMERICA | BLM18AG601SN1D | G | PWA BOM | In New BOM |
|  |  |  | 720101L00-026-G | FB,600 Ohm@100MHz,+/-25%,200mA,500mOhm,G,SMD0603 | SAMSUNG SEMICONDUCTOR | CIM10U601NC | G | PWA BOM | In New BOM |
|  |  |  | 720101L00-074-G | FB,600Ohm@100MHz,+/-25%,200mA,500mOhm,SMD0603,G | CHILISIN ELECTRONICS CORP. | SBK160808T-601Y-N | G | PWA BOM | In New BOM |
|  |  |  | 720105E04-016-G | FB,600Ohm@100MHz,+/-25%,500mA,400mOhm,SMD0603,G | TDK ELECTRONICS EUROPE GMBH | MMZ1608B601CTAH0 | G | PWA BOM | In New BOM |
|  | L24 | 1 | 720101L00-015-G | FB,600 Ohm@100MHz,+/-25%,200mA,500mOhm,G,SMD0603 | MURATA ELEC. NORTH AMERICA | BLM18AG601SN1D | G | PWA BOM | In Old BOM |
| 2 | PSCL1 | 1 | 63034FP00-088-G | IND,220nH@100KHz,+/-20%,23A,2.8mOhm,SHLD,G,SMD | COOPER BUSSMANN, INC. | HCM0703-R22-R | G | PWA BOM | In New BOM |
|  |  |  | 63034UP00-15A-G | IND,220nH@100KHz,+/-20%,23A,2.8mOhm,SHLD,G,SMD | The Inter-Technical Group, Inc. | SMHC2511-R22MHF |  | PWA BOM | In New BOM |
|  | PSCL1 | 1 | 63034FP00-088-G | IND,220nH@100KHz,+/-20%,23A,2.8mOhm,SHLD,G,SMD | COOPER BUSSMANN, INC. | HCM0703-R22-R | G | PWA BOM | In Old BOM |
| 3 | PSRR19 | 1 | 61100YB00-017-G | RES,2.94KOhm,+/-0.1%,1/16W,G,SMD0402 | KOA SPEER ELECTRONICS, INC. | RN731ETTP2941B25 | G | PWA BOM | In New BOM |
|  |  |  | 61100YB00-011-G | RES,2.94KOhm,+/-0.1%,1/16W,G,SMD0402 | YAGEO CORPORATION COMPONENT | RT0402BRD072K94L | G | PWA BOM | In New BOM |
|  |  |  | 61100YB00-044-G | RES,2.94KOhm,+/-0.1%,1/16W,G,SMD0402 | TA-I TECHNOLOGY CO., LTD | RB04BTP2941 | G | PWA BOM | In New BOM |
|  | PSRR19 | 1 | 61100YB00-017-G | RES,2.94KOhm,+/-0.1%,1/16W,G,SMD0402 | KOA SPEER ELECTRONICS, INC. | RN731ETTP2941B25 | G | PWA BOM | In Old BOM |
| 4 | Q4,Q6 | 2 | 51040EK00-185-G | MOS P,FDMS6681Z,30V,49A,5m@4.5V,G,Power56-8,SMD | FAIRCHILD SEMICONDUCTOR CORP | FDMS6681Z | G | PWA BOM | In New BOM |
|  |  |  | 51040ME00-262-G | MOS P,AON6403L,30V,85A,4.3m@4.5V,G,DFN-8,SMD | Alpha & Omega Semiconductor Inc. | AON6403L | G | PWA BOM | In New BOM |
|  |  |  | 51040MH00-221-G | MOS P,BSC030P03NS3 G,30V,100A,4.6m@6V,G,TDSON-8,SMD | INFINEON TECHNOLOGIES CORP. | BSC030P03NS3 G | G | PWA BOM | In New BOM |
|  | Q4,Q6 | 2 | 51040EK00-185-G | MOS P,FDMS6681Z,30V,49A,5m@4.5V,G,Power56-8,SMD | FAIRCHILD SEMICONDUCTOR CORP | FDMS6681Z | G | PWA BOM | In Old BOM |
| 5 | U_EXP_FLASH1 | 1 | 41050R700-396-G | Flash,S29GL128S10TFIV20,2.7~3.6V,128M,CFI,G,TSOP-56,SMD | SPANSION INTERNATIONAL LLC | S29GL128S10TFIV20 | G | PWA BOM | In New BOM |
|  |  |  | 41050N100-216-G | Flash,JS28F128M29EWLA,2.7~3.6V,128M,CFI,G,TSOP-56,SMD | MICRON TECHNOLOGY, INC. | JS28F128M29EWLA | G | PWA BOM | In New BOM |
|  |  |  | 41050UE00-233-G | Flash,MX29GL128FDT2I-11G,2.7~3.6V,128M,CFI,G,TSOP-56,SMD | MACRONIX INTERNATIONAL CO.,LTD. | MX29GL128FDT2I-11G | G | PWA BOM | In New BOM |
|  | U_EXP_FLASH1 | 1 | 41050R700-396-G | Flash,S29GL128S10TFIV20,2.7~3.6V,128M,CFI,G,TSOP-56,SMD | SPANSION INTERNATIONAL LLC | S29GL128S10TFIV20 | G | PWA BOM | In Old BOM |
| 6 | U_EXP_FRU1 | 1 | 41040DK00-191-G | EEPROM,AT24C04C-SSHM-T,1.7~5.5V,4K,2-wire,G,SOIC-8,SMD | ATMEL CORPORATION | AT24C04C-SSHM-T | G | PWA BOM | In New BOM |
|  |  |  | 41040C200-223-G | EEPROM,CAT24C04WI-GT3,1.8~5.5V,4K,I2C,G,SOIC-8,SMD | ON SEMICONDUCTOR CORP | CAT24C04WI-GT3 | G | PWA BOM | In New BOM |
|  |  |  | 410405J00-214-G | EEPROM,M24C04-RMN6TP,1.8~5.5V,4K,2-Wire Serial,G,SO-8,SMD | STMICROELECTRONICS | M24C04-RMN6TP | G | PWA BOM | In New BOM |
|  | U_EXP_FRU1 | 1 | 41040DK00-191-G | EEPROM,AT24C04C-SSHM-T,1.7~5.5V,4K,2-wire,G,SOIC-8,SMD | ATMEL CORPORATION | AT24C04C-SSHM-T | G | PWA BOM | In Old BOM |
| 7 | U_EXP_NVSRAM1 | 1 | 420103500-18R-G | SRAM,MR0D08BMA45R,3.3V,128K*8,G,FBGA-48,SMD | Everspin Technologies, Inc. | MR0D08BMA45R | G | PWA BOM | In New BOM |
|  |  |  | 420103G00-244-G | SRAM,CY14V101LA-BA45XIT,3.0~3.6V,1M,G,FBGA-48,SMD | CYPRESS SEMICONDUCTOR CORP | CY14V101LA-BA45XIT | G | PWA BOM | In New BOM |
|  | U_EXP_NVSRAM1 | 1 | 420103500-18R-G | SRAM,MR0D08BMA45R,3.3V,128K*8,G,FBGA-48,SMD | Everspin Technologies, Inc. | MR0D08BMA45R | G | PWA BOM | In Old BOM |
| 8 | U6 | 1 | 32022FF00-173-G | IC,Power Controller,MAX6315US29D1+T,G,SOT-143-4,SMD | MAXIM INTEGRATED PRODUCTS, INC. | MAX6315US29D1+T | G | PWA BOM | In New BOM |
|  |  |  | 32022NH00-252-G | IC,Power Controller,PT7M6315US29D1TBEX,G,SOT143-4,SMD | PERICOM SEMICONDUCTOR CORP | PT7M6315US29D1TBEX | G | PWA BOM | In New BOM |
|  | U6 | 1 | 32022FF00-173-G | IC,Power Controller,MAX6315US29D1+T,G,SOT-143-4,SMD | MAXIM INTEGRATED PRODUCTS, INC. | MAX6315US29D1+T | G | PWA BOM | In Old BOM |
| ##### Change Revision |  |  |  |  |  |  |  |  |  |
| Sheet | REV OF BOM | CUSTOMER | CUSTOMER P/N | PWA PN | PWA DESCRIPTION | PWA REV | DATE | Remark |  |
| OOOOOOOOOOOOOOOOOOOOOOOOOOOOOOOOOOOOOOOOOOOOOOOOOOOOOOOOOOOOOOOOOOOOOOOOOOOOOOOOOOOOOOOOOO | OOOOOOOOOOOOOOOOOOOOOOOOOOOOOOOOOOOOOOOOOOOOOOOOOOOOOOOOOOOOOOOOOOOOOOOOOOOOOOOOOOOOOOOOOO | OOOOOOOOOOOOOOOOOOOOOOOOOOOOOOOOOOOOOOOOOOOOOOOOOOOOOOOOOOOOOOOOOOOOOOOOOOOOOOOOOOOOOOOOOO | OOOOOOOOOOOOOOOOOOOOOOOOOOOOOOOOOOOOOOOOOOOOOOOOOOOOOOOOOOOOOOOOOOOOOOOOOOOOOOOOOOOOOOOOOO | OOOOOOOOOOOOOOOOOOOOOOOOOOOOOOOOOOOOOOOOOOOOOOOOOOOOOOOOOOOOOOOOOOOOOOOOOOOOOOOOOOOOOOOOOO | OOOOOOOOOOOOOOOOOOOOOOOOOOOOOOOOOOOOOOOOOOOOOOOOOOOOOOOOOOOOOOOOOOOOOOOOOOOOOOOOOOOOOOOOOO | OOOOOOOOOOOOOOOOOOOOOOOOOOOOOOOOOOOOOOOOOOOOOOOOOOOOOOOOOOOOOOOOOOOOOOOOOOOOOOOOOOOOOOOOOO | OOOOOOOOOOOOOOOOOOOOOOOOOOOOOOOOOOOOOOOOOOOOOOOOOOOOOOOOOOOOOOOOOOOOOOOOOOOOOOOOOOOOOOOOOO | OOOOOOOOOOOOOOOOOOOOOOOOOOOOOOOOOOOOOOOOOOOOOOOOOOOOOOOOOOOOOOOOOOOOOOOOOOOOOOOOOOOOOOOOOO | OOOOOOOOOOOOOOOOOOOOOOOOOOOOOOOOOOOOOOOOOOOOOOOOOOOOOOOOOOOOOOOOOOOOOOOOOOOOOOOOOOOOOOOOOO |
| Second Source Change |  |  |  |  |  |  |  |  |  |
| Item | Location | Change Type | Foxconn P/N | Part Description | Manufacturer Full Name | Manufacturer P/N | RoHS | Sheet |  |
| 1 | L24 |  | 720101L00-015-G | FB,600 Ohm@100MHz,+/-25%,200mA,500mOhm,G,SMD0603 | MURATA ELEC. NORTH AMERICA | BLM18AG601SN1D | G | PWA BOM |  |
|  |  | ADD | 720101L00-026-G | FB,600 Ohm@100MHz,+/-25%,200mA,500mOhm,G,SMD0603 | SAMSUNG SEMICONDUCTOR | CIM10U601NC | G | PWA BOM |  |
|  |  | ADD | 720101L00-074-G | FB,600Ohm@100MHz,+/-25%,200mA,500mOhm,SMD0603,G | CHILISIN ELECTRONICS CORP. | SBK160808T-601Y-N | G | PWA BOM |  |
|  |  | ADD | 720105E04-016-G | FB,600Ohm@100MHz,+/-25%,500mA,400mOhm,SMD0603,G | TDK ELECTRONICS EUROPE GMBH | MMZ1608B601CTAH0 | G | PWA BOM |  |
| 2 | PSCL1 |  | 63034FP00-088-G | IND,220nH@100KHz,+/-20%,23A,2.8mOhm,SHLD,G,SMD | COOPER BUSSMANN, INC. | HCM0703-R22-R | G | PWA BOM |  |
|  |  | ADD | 63034UP00-15A-G | IND,220nH@100KHz,+/-20%,23A,2.8mOhm,SHLD,G,SMD | The Inter-Technical Group, Inc. | SMHC2511-R22MHF |  | PWA BOM |  |
| 3 | PSRR19 |  | 61100YB00-017-G | RES,2.94KOhm,+/-0.1%,1/16W,G,SMD0402 | KOA SPEER ELECTRONICS, INC. | RN731ETTP2941B25 | G | PWA BOM |  |
|  |  | ADD | 61100YB00-011-G | RES,2.94KOhm,+/-0.1%,1/16W,G,SMD0402 | YAGEO CORPORATION COMPONENT | RT0402BRD072K94L | G | PWA BOM |  |
|  |  | ADD | 61100YB00-044-G | RES,2.94KOhm,+/-0.1%,1/16W,G,SMD0402 | TA-I TECHNOLOGY CO., LTD | RB04BTP2941 | G | PWA BOM |  |
| 4 | Q4,Q6 |  | 51040EK00-185-G | MOS P,FDMS6681Z,30V,49A,5m@4.5V,G,Power56-8,SMD | FAIRCHILD SEMICONDUCTOR CORP | FDMS6681Z | G | PWA BOM |  |
|  |  | ADD | 51040ME00-262-G | MOS P,AON6403L,30V,85A,4.3m@4.5V,G,DFN-8,SMD | Alpha & Omega Semiconductor Inc. | AON6403L | G | PWA BOM |  |
|  |  | ADD | 51040MH00-221-G | MOS P,BSC030P03NS3 G,30V,100A,4.6m@6V,G,TDSON-8,SMD | INFINEON TECHNOLOGIES CORP. | BSC030P03NS3 G | G | PWA BOM |  |
| 5 | U_EXP_FLASH1 |  | 41050R700-396-G | Flash,S29GL128S10TFIV20,2.7~3.6V,128M,CFI,G,TSOP-56,SMD | SPANSION INTERNATIONAL LLC | S29GL128S10TFIV20 | G | PWA BOM |  |
|  |  | ADD | 41050N100-216-G | Flash,JS28F128M29EWLA,2.7~3.6V,128M,CFI,G,TSOP-56,SMD | MICRON TECHNOLOGY, INC. | JS28F128M29EWLA | G | PWA BOM |  |
|  |  | ADD | 41050UE00-233-G | Flash,MX29GL128FDT2I-11G,2.7~3.6V,128M,CFI,G,TSOP-56,SMD | MACRONIX INTERNATIONAL CO.,LTD. | MX29GL128FDT2I-11G | G | PWA BOM |  |
| 6 | U_EXP_FRU1 |  | 41040DK00-191-G | EEPROM,AT24C04C-SSHM-T,1.7~5.5V,4K,2-wire,G,SOIC-8,SMD | ATMEL CORPORATION | AT24C04C-SSHM-T | G | PWA BOM |  |
|  |  | ADD | 41040C200-223-G | EEPROM,CAT24C04WI-GT3,1.8~5.5V,4K,I2C,G,SOIC-8,SMD | ON SEMICONDUCTOR CORP | CAT24C04WI-GT3 | G | PWA BOM |  |
|  |  | ADD | 410405J00-214-G | EEPROM,M24C04-RMN6TP,1.8~5.5V,4K,2-Wire Serial,G,SO-8,SMD | STMICROELECTRONICS | M24C04-RMN6TP | G | PWA BOM |  |
| 7 | U_EXP_NVSRAM1 |  | 420103500-18R-G | SRAM,MR0D08BMA45R,3.3V,128K*8,G,FBGA-48,SMD | Everspin Technologies, Inc. | MR0D08BMA45R | G | PWA BOM |  |
|  |  | ADD | 420103G00-244-G | SRAM,CY14V101LA-BA45XIT,3.0~3.6V,1M,G,FBGA-48,SMD | CYPRESS SEMICONDUCTOR CORP | CY14V101LA-BA45XIT | G | PWA BOM |  |
| 8 | U6 |  | 32022FF00-173-G | IC,Power Controller,MAX6315US29D1+T,G,SOT-143-4,SMD | MAXIM INTEGRATED PRODUCTS, INC. | MAX6315US29D1+T | G | PWA BOM |  |
|  |  | ADD | 32022NH00-252-G | IC,Power Controller,PT7M6315US29D1TBEX,G,SOT143-4,SMD | PERICOM SEMICONDUCTOR CORP | PT7M6315US29D1TBEX | G | PWA BOM |  |
| OOOOOOOOOOOOOOOOOOOOOOOOOOOOOOOOOOOOOOOOOOOOOOOOOOOOOOOOOOOOOOOOOOOOOOOOOOOOOOOOOOOOOOOOOO | OOOOOOOOOOOOOOOOOOOOOOOOOOOOOOOOOOOOOOOOOOOOOOOOOOOOOOOOOOOOOOOOOOOOOOOOOOOOOOOOOOOOOOOOOO | OOOOOOOOOOOOOOOOOOOOOOOOOOOOOOOOOOOOOOOOOOOOOOOOOOOOOOOOOOOOOOOOOOOOOOOOOOOOOOOOOOOOOOOOOO | OOOOOOOOOOOOOOOOOOOOOOOOOOOOOOOOOOOOOOOOOOOOOOOOOOOOOOOOOOOOOOOOOOOOOOOOOOOOOOOOOOOOOOOOOO | OOOOOOOOOOOOOOOOOOOOOOOOOOOOOOOOOOOOOOOOOOOOOOOOOOOOOOOOOOOOOOOOOOOOOOOOOOOOOOOOOOOOOOOOOO | OOOOOOOOOOOOOOOOOOOOOOOOOOOOOOOOOOOOOOOOOOOOOOOOOOOOOOOOOOOOOOOOOOOOOOOOOOOOOOOOOOOOOOOOOO | OOOOOOOOOOOOOOOOOOOOOOOOOOOOOOOOOOOOOOOOOOOOOOOOOOOOOOOOOOOOOOOOOOOOOOOOOOOOOOOOOOOOOOOOOO | OOOOOOOOOOOOOOOOOOOOOOOOOOOOOOOOOOOOOOOOOOOOOOOOOOOOOOOOOOOOOOOOOOOOOOOOOOOOOOOOOOOOOOOOOO | OOOOOOOOOOOOOOOOOOOOOOOOOOOOOOOOOOOOOOOOOOOOOOOOOOOOOOOOOOOOOOOOOOOOOOOOOOOOOOOOOOOOOOOOOO | OOOOOOOOOOOOOOOOOOOOOOOOOOOOOOOOOOOOOOOOOOOOOOOOOOOOOOOOOOOOOOOOOOOOOOOOOOOOOOOOOOOOOOOOOO |
| Master Materials Change |  |  |  |  |  |  |  |  |  |
| Item | Foxconn P/N | Orig._Usage | New_Usage | Part Description | Manufacturer Full Name | Manufacturer P/N | RoHS | Location | Sheet |
| OOOOOOOOOOOOOOOOOOOOOOOOOOOOOOOOOOOOOOOOOOOOOOOOOOOOOOOOOOOOOOOOOOOOOOOOOOOOOOOOOOOOOOOOOO | OOOOOOOOOOOOOOOOOOOOOOOOOOOOOOOOOOOOOOOOOOOOOOOOOOOOOOOOOOOOOOOOOOOOOOOOOOOOOOOOOOOOOOOOOO | OOOOOOOOOOOOOOOOOOOOOOOOOOOOOOOOOOOOOOOOOOOOOOOOOOOOOOOOOOOOOOOOOOOOOOOOOOOOOOOOOOOOOOOOOO | OOOOOOOOOOOOOOOOOOOOOOOOOOOOOOOOOOOOOOOOOOOOOOOOOOOOOOOOOOOOOOOOOOOOOOOOOOOOOOOOOOOOOOOOOO | OOOOOOOOOOOOOOOOOOOOOOOOOOOOOOOOOOOOOOOOOOOOOOOOOOOOOOOOOOOOOOOOOOOOOOOOOOOOOOOOOOOOOOOOOO | OOOOOOOOOOOOOOOOOOOOOOOOOOOOOOOOOOOOOOOOOOOOOOOOOOOOOOOOOOOOOOOOOOOOOOOOOOOOOOOOOOOOOOOOOO | OOOOOOOOOOOOOOOOOOOOOOOOOOOOOOOOOOOOOOOOOOOOOOOOOOOOOOOOOOOOOOOOOOOOOOOOOOOOOOOOOOOOOOOOOO | OOOOOOOOOOOOOOOOOOOOOOOOOOOOOOOOOOOOOOOOOOOOOOOOOOOOOOOOOOOOOOOOOOOOOOOOOOOOOOOOOOOOOOOOOO | OOOOOOOOOOOOOOOOOOOOOOOOOOOOOOOOOOOOOOOOOOOOOOOOOOOOOOOOOOOOOOOOOOOOOOOOOOOOOOOOOOOOOOOOOO | OOOOOOOOOOOOOOOOOOOOOOOOOOOOOOOOOOOOOOOOOOOOOOOOOOOOOOOOOOOOOOOOOOOOOOOOOOOOOOOOOOOOOOOOOO |
| BOM Change List Date:Thu Nov 23 13:58:43 GMT+08:00 2017 |  |  |  |  |  |  |  |  |  |
| New BOM file : E:\barreleye g2\1123\expander 1123.xls |  |  |  |  |  |  |  |  |  |
| Old BOM file : E:\barreleye g2\1123\expander 1103.xls |  |  |  |  |  |  |  |  |  |
| ##### Add Parts |  |  |  |  |  |  |  |  |  |
| Item | Location | Qty | Foxconn P/N | Part Description | Manufacturer Full Name | Manufacturer P/N | RoHS | Sheet |  |
| ##### Remove Parts |  |  |  |  |  |  |  |  |  |
| Item | Location | Qty | Foxconn P/N | Part Description | Manufacturer Full Name | Manufacturer P/N | RoHS | Sheet |  |
| ##### Change Parts |  |  |  |  |  |  |  |  |  |
| Item | Location | Qty | Foxconn P/N | Part Description | Manufacturer Full Name | Manufacturer P/N | RoHS | Sheet | Remark |
| 1 | Q5 | 1 | 51030S400-185-G | MOS N,FDMC8884,30V,9A,30m@4.5V,G,Power33-8,SMD | FAIRCHILD SEMICONDUCTOR CORP | FDMC8884 | G | PWA BOM | In New BOM |
|  |  |  | 510505E00-221-G | MOS N/N,BSC150N03LD G,30V,8A,22m@4.5V,G,TDSON-8,SMD | INFINEON | BSC150N03LD G | G | PWA BOM | In New BOM |
|  |  |  | 51030SM00-029-G | MOSFET-N,SIS412DN-T1-GE3,30V,12A,24mOhm@Vgs=10V,30mOhm@Vgs=4.5V,PowerPAK1212,8P,G | VISHAY ENTER TECHNO LOGY.INC | SIS412DN-T1-GE3 | G | PWA BOM | In New BOM |
|  |  |  | 51030U700-223-G | MOS N,NTMFS4823NT1G,30V,10.8A,18m@4.5V,G,SO-8FL,SMD | ON SEMICONDUCTOR CORP | NTMFS4823NT1G | G | PWA BOM | In New BOM |
|  |  |  | 51031BT00-223-G | MOS N,NTTFS4930NTAG,30V,7.2A,30m@4.5V,G,WDFN-8,SMD | ON SEMICONDUCTOR CORP | NTTFS4930NTAG | G | PWA BOM | In New BOM |
|  | Q5 | 1 | 51030S400-185-G | MOS N,FDMC8884,30V,9A,30m@4.5V,G,Power33-8,SMD | FAIRCHILD SEMICONDUCTOR CORP | FDMC8884 | G | PWA BOM | In Old BOM |
|  |  |  | 510505E00-221-G | MOS N/N,BSC150N03LD G,30V,8A,22m@4.5V,G,TDSON-8,SMD | INFINEON | BSC150N03LD G | G | PWA BOM | In Old BOM |
|  |  |  | 51030RB00-029-G | MOS N,Si7326DN-T1-GE3,30V,6.5A,30m@4.5V,G,PowerPAK1212-8,SMD | VISHAY | SI7326DN-T1-GE3 | G | PWA BOM | In Old BOM |
|  |  |  | 51030U700-223-G | MOS N,NTMFS4823NT1G,30V,10.8A,18m@4.5V,G,SO-8FL,SMD | ON SEMICONDUCTOR CORP | NTMFS4823NT1G | G | PWA BOM | In Old BOM |
|  |  |  | 51031BT00-223-G | MOS N,NTTFS4930NTAG,30V,7.2A,30m@4.5V,G,WDFN-8,SMD | ON SEMICONDUCTOR CORP | NTTFS4930NTAG | G | PWA BOM | In Old BOM |
| 2 | U_EXP_FLASH1 | 1 | 41050R700-396-G | Flash,S29GL128S10TFIV20,2.7~3.6V,128M,CFI,G,TSOP-56,SMD | SPANSION INTERNATIONAL LLC | S29GL128S10TFIV20 | G | PWA BOM | In New BOM |
|  |  |  | 410515T00-216-G | Flash,MT28EW128ABA1LJS-0SIT,2.7V~3.6V,128M,CFI,G,TSOP-56,SMD | MICRON TECHNOLOGY, INC. | MT28EW128ABA1LJS-0SIT | G | PWA BOM | In New BOM |
|  |  |  | 41050UE00-233-G | Flash,MX29GL128FDT2I-11G,2.7~3.6V,128M,CFI,G,TSOP-56,SMD | MACRONIX INTERNATIONAL CO.,LTD. | MX29GL128FDT2I-11G | G | PWA BOM | In New BOM |
|  | U_EXP_FLASH1 | 1 | 41050R700-396-G | Flash,S29GL128S10TFIV20,2.7~3.6V,128M,CFI,G,TSOP-56,SMD | SPANSION INTERNATIONAL LLC | S29GL128S10TFIV20 | G | PWA BOM | In Old BOM |
|  |  |  | 41050N100-216-G | Flash,JS28F128M29EWLA,2.7~3.6V,128M,CFI,G,TSOP-56,SMD | MICRON TECHNOLOGY, INC. | JS28F128M29EWLA | G | PWA BOM | In Old BOM |
|  |  |  | 41050UE00-233-G | Flash,MX29GL128FDT2I-11G,2.7~3.6V,128M,CFI,G,TSOP-56,SMD | MACRONIX INTERNATIONAL CO.,LTD. | MX29GL128FDT2I-11G | G | PWA BOM | In Old BOM |
| ##### Change Revision |  |  |  |  |  |  |  |  |  |
| Sheet | REV OF BOM | CUSTOMER | CUSTOMER P/N | PWA PN | PWA DESCRIPTION | PWA REV | DATE | Remark |  |
| OOOOOOOOOOOOOOOOOOOOOOOOOOOOOOOOOOOOOOOOOOOOOOOOOOOOOOOOOOOOOOOOOOOOOOOOOOOOOOOOOOOOOOOOOO | OOOOOOOOOOOOOOOOOOOOOOOOOOOOOOOOOOOOOOOOOOOOOOOOOOOOOOOOOOOOOOOOOOOOOOOOOOOOOOOOOOOOOOOOOO | OOOOOOOOOOOOOOOOOOOOOOOOOOOOOOOOOOOOOOOOOOOOOOOOOOOOOOOOOOOOOOOOOOOOOOOOOOOOOOOOOOOOOOOOOO | OOOOOOOOOOOOOOOOOOOOOOOOOOOOOOOOOOOOOOOOOOOOOOOOOOOOOOOOOOOOOOOOOOOOOOOOOOOOOOOOOOOOOOOOOO | OOOOOOOOOOOOOOOOOOOOOOOOOOOOOOOOOOOOOOOOOOOOOOOOOOOOOOOOOOOOOOOOOOOOOOOOOOOOOOOOOOOOOOOOOO | OOOOOOOOOOOOOOOOOOOOOOOOOOOOOOOOOOOOOOOOOOOOOOOOOOOOOOOOOOOOOOOOOOOOOOOOOOOOOOOOOOOOOOOOOO | OOOOOOOOOOOOOOOOOOOOOOOOOOOOOOOOOOOOOOOOOOOOOOOOOOOOOOOOOOOOOOOOOOOOOOOOOOOOOOOOOOOOOOOOOO | OOOOOOOOOOOOOOOOOOOOOOOOOOOOOOOOOOOOOOOOOOOOOOOOOOOOOOOOOOOOOOOOOOOOOOOOOOOOOOOOOOOOOOOOOO | OOOOOOOOOOOOOOOOOOOOOOOOOOOOOOOOOOOOOOOOOOOOOOOOOOOOOOOOOOOOOOOOOOOOOOOOOOOOOOOOOOOOOOOOOO | OOOOOOOOOOOOOOOOOOOOOOOOOOOOOOOOOOOOOOOOOOOOOOOOOOOOOOOOOOOOOOOOOOOOOOOOOOOOOOOOOOOOOOOOOO |
| Second Source Change |  |  |  |  |  |  |  |  |  |
| Item | Location | Change Type | Foxconn P/N | Part Description | Manufacturer Full Name | Manufacturer P/N | RoHS | Sheet |  |
| 1 | Q5 |  | 51030S400-185-G | MOS N,FDMC8884,30V,9A,30m@4.5V,G,Power33-8,SMD | FAIRCHILD SEMICONDUCTOR CORP | FDMC8884 | G | PWA BOM |  |
|  |  | NO | 510505E00-221-G | MOS N/N,BSC150N03LD G,30V,8A,22m@4.5V,G,TDSON-8,SMD | INFINEON | BSC150N03LD G | G | PWA BOM |  |
|  |  | ADD | 51030SM00-029-G | MOSFET-N,SIS412DN-T1-GE3,30V,12A,24mOhm@Vgs=10V,30mOhm@Vgs=4.5V,PowerPAK1212,8P,G | VISHAY ENTER TECHNO LOGY.INC | SIS412DN-T1-GE3 | G | PWA BOM |  |
|  |  | NO | 51030U700-223-G | MOS N,NTMFS4823NT1G,30V,10.8A,18m@4.5V,G,SO-8FL,SMD | ON SEMICONDUCTOR CORP | NTMFS4823NT1G | G | PWA BOM |  |
|  |  | NO | 51031BT00-223-G | MOS N,NTTFS4930NTAG,30V,7.2A,30m@4.5V,G,WDFN-8,SMD | ON SEMICONDUCTOR CORP | NTTFS4930NTAG | G | PWA BOM |  |
|  |  | Delete | 51030RB00-029-G | MOS N,Si7326DN-T1-GE3,30V,6.5A,30m@4.5V,G,PowerPAK1212-8,SMD | VISHAY | SI7326DN-T1-GE3 | G | PWA BOM |  |
| 2 | U_EXP_FLASH1 |  | 41050R700-396-G | Flash,S29GL128S10TFIV20,2.7~3.6V,128M,CFI,G,TSOP-56,SMD | SPANSION INTERNATIONAL LLC | S29GL128S10TFIV20 | G | PWA BOM |  |
|  |  | ADD | 410515T00-216-G | Flash,MT28EW128ABA1LJS-0SIT,2.7V~3.6V,128M,CFI,G,TSOP-56,SMD | MICRON TECHNOLOGY, INC. | MT28EW128ABA1LJS-0SIT | G | PWA BOM |  |
|  |  | NO | 41050UE00-233-G | Flash,MX29GL128FDT2I-11G,2.7~3.6V,128M,CFI,G,TSOP-56,SMD | MACRONIX INTERNATIONAL CO.,LTD. | MX29GL128FDT2I-11G | G | PWA BOM |  |
|  |  | Delete | 41050N100-216-G | Flash,JS28F128M29EWLA,2.7~3.6V,128M,CFI,G,TSOP-56,SMD | MICRON TECHNOLOGY, INC. | JS28F128M29EWLA | G | PWA BOM |  |
| OOOOOOOOOOOOOOOOOOOOOOOOOOOOOOOOOOOOOOOOOOOOOOOOOOOOOOOOOOOOOOOOOOOOOOOOOOOOOOOOOOOOOOOOOO | OOOOOOOOOOOOOOOOOOOOOOOOOOOOOOOOOOOOOOOOOOOOOOOOOOOOOOOOOOOOOOOOOOOOOOOOOOOOOOOOOOOOOOOOOO | OOOOOOOOOOOOOOOOOOOOOOOOOOOOOOOOOOOOOOOOOOOOOOOOOOOOOOOOOOOOOOOOOOOOOOOOOOOOOOOOOOOOOOOOOO | OOOOOOOOOOOOOOOOOOOOOOOOOOOOOOOOOOOOOOOOOOOOOOOOOOOOOOOOOOOOOOOOOOOOOOOOOOOOOOOOOOOOOOOOOO | OOOOOOOOOOOOOOOOOOOOOOOOOOOOOOOOOOOOOOOOOOOOOOOOOOOOOOOOOOOOOOOOOOOOOOOOOOOOOOOOOOOOOOOOOO | OOOOOOOOOOOOOOOOOOOOOOOOOOOOOOOOOOOOOOOOOOOOOOOOOOOOOOOOOOOOOOOOOOOOOOOOOOOOOOOOOOOOOOOOOO | OOOOOOOOOOOOOOOOOOOOOOOOOOOOOOOOOOOOOOOOOOOOOOOOOOOOOOOOOOOOOOOOOOOOOOOOOOOOOOOOOOOOOOOOOO | OOOOOOOOOOOOOOOOOOOOOOOOOOOOOOOOOOOOOOOOOOOOOOOOOOOOOOOOOOOOOOOOOOOOOOOOOOOOOOOOOOOOOOOOOO | OOOOOOOOOOOOOOOOOOOOOOOOOOOOOOOOOOOOOOOOOOOOOOOOOOOOOOOOOOOOOOOOOOOOOOOOOOOOOOOOOOOOOOOOOO | OOOOOOOOOOOOOOOOOOOOOOOOOOOOOOOOOOOOOOOOOOOOOOOOOOOOOOOOOOOOOOOOOOOOOOOOOOOOOOOOOOOOOOOOOO |
| Master Materials Change |  |  |  |  |  |  |  |  |  |
| Item | Foxconn P/N | Orig._Usage | New_Usage | Part Description | Manufacturer Full Name | Manufacturer P/N | RoHS | Location | Sheet |
| OOOOOOOOOOOOOOOOOOOOOOOOOOOOOOOOOOOOOOOOOOOOOOOOOOOOOOOOOOOOOOOOOOOOOOOOOOOOOOOOOOOOOOOOOO | OOOOOOOOOOOOOOOOOOOOOOOOOOOOOOOOOOOOOOOOOOOOOOOOOOOOOOOOOOOOOOOOOOOOOOOOOOOOOOOOOOOOOOOOOO | OOOOOOOOOOOOOOOOOOOOOOOOOOOOOOOOOOOOOOOOOOOOOOOOOOOOOOOOOOOOOOOOOOOOOOOOOOOOOOOOOOOOOOOOOO | OOOOOOOOOOOOOOOOOOOOOOOOOOOOOOOOOOOOOOOOOOOOOOOOOOOOOOOOOOOOOOOOOOOOOOOOOOOOOOOOOOOOOOOOOO | OOOOOOOOOOOOOOOOOOOOOOOOOOOOOOOOOOOOOOOOOOOOOOOOOOOOOOOOOOOOOOOOOOOOOOOOOOOOOOOOOOOOOOOOOO | OOOOOOOOOOOOOOOOOOOOOOOOOOOOOOOOOOOOOOOOOOOOOOOOOOOOOOOOOOOOOOOOOOOOOOOOOOOOOOOOOOOOOOOOOO | OOOOOOOOOOOOOOOOOOOOOOOOOOOOOOOOOOOOOOOOOOOOOOOOOOOOOOOOOOOOOOOOOOOOOOOOOOOOOOOOOOOOOOOOOO | OOOOOOOOOOOOOOOOOOOOOOOOOOOOOOOOOOOOOOOOOOOOOOOOOOOOOOOOOOOOOOOOOOOOOOOOOOOOOOOOOOOOOOOOOO | OOOOOOOOOOOOOOOOOOOOOOOOOOOOOOOOOOOOOOOOOOOOOOOOOOOOOOOOOOOOOOOOOOOOOOOOOOOOOOOOOOOOOOOOOO | OOOOOOOOOOOOOOOOOOOOOOOOOOOOOOOOOOOOOOOOOOOOOOOOOOOOOOOOOOOOOOOOOOOOOOOOOOOOOOOOOOOOOOOOOO |
| TLA Parts Change |  |  |  |  |  |  |  |  |  |
| Item | Foxconn P/N | Qty | Part Description | Manufacturer Full Name | Manufacturer P/N | RoHS | Location | Remark | BOM |
| BOM Change List Date:Fri Dec 08 14:26:32 GMT+08:00 2017 |  |  |  |  |  |  |  |  |  |
| New BOM file : E:\barreleye g2\1208\EXPANDER 1208.xls |  |  |  |  |  |  |  |  |  |
| Old BOM file : E:\barreleye g2\1208\EXPANDER 1123.xls |  |  |  |  |  |  |  |  |  |
| ##### Add Parts |  |  |  |  |  |  |  |  |  |
| Item | Location | Qty | Foxconn P/N | Part Description | Manufacturer Full Name | Manufacturer P/N | RoHS | Sheet |  |
| ##### Remove Parts |  |  |  |  |  |  |  |  |  |
| Item | Location | Qty | Foxconn P/N | Part Description | Manufacturer Full Name | Manufacturer P/N | RoHS | Sheet |  |
| ##### Change Parts |  |  |  |  |  |  |  |  |  |
| Item | Location | Qty | Foxconn P/N | Part Description | Manufacturer Full Name | Manufacturer P/N | RoHS | Sheet | Remark |
| 1 | L24 | 1 | 720101L00-015-G | FB,600 Ohm@100MHz,+/-25%,200mA,500mOhm,G,SMD0603 | MURATA ELEC. NORTH AMERICA | BLM18AG601SN1D | G | PWA BOM | In New BOM |
|  |  |  | 720101L00-074-G | FB,600Ohm@100MHz,+/-25%,200mA,500mOhm,SMD0603,G | CHILISIN ELECTRONICS CORP. | SBK160808T-601Y-N | G | PWA BOM | In New BOM |
|  |  |  | 720105E04-016-G | FB,600Ohm@100MHz,+/-25%,500mA,400mOhm,SMD0603,G | TDK ELECTRONICS EUROPE GMBH | MMZ1608B601CTAH0 | G | PWA BOM | In New BOM |
|  | L24 | 1 | 720101L00-015-G | FB,600 Ohm@100MHz,+/-25%,200mA,500mOhm,G,SMD0603 | MURATA ELEC. NORTH AMERICA | BLM18AG601SN1D | G | PWA BOM | In Old BOM |
|  |  |  | 720101L00-026-G | FB,600 Ohm@100MHz,+/-25%,200mA,500mOhm,G,SMD0603 | SAMSUNG SEMICONDUCTOR | CIM10U601NC | G | PWA BOM | In Old BOM |
|  |  |  | 720101L00-074-G | FB,600Ohm@100MHz,+/-25%,200mA,500mOhm,SMD0603,G | CHILISIN ELECTRONICS CORP. | SBK160808T-601Y-N | G | PWA BOM | In Old BOM |
|  |  |  | 720105E04-016-G | FB,600Ohm@100MHz,+/-25%,500mA,400mOhm,SMD0603,G | TDK ELECTRONICS EUROPE GMBH | MMZ1608B601CTAH0 | G | PWA BOM | In Old BOM |
| 2 | Q5 | 1 | 51030S400-185-G | MOS N,FDMC8884,30V,9A,30m@4.5V,G,Power33-8,SMD | FAIRCHILD SEMICONDUCTOR CORP | FDMC8884 | G | PWA BOM | In New BOM |
|  |  |  | 51030SM00-029-G | MOSFET-N,SIS412DN-T1-GE3,30V,12A,24mOhm@Vgs=10V,30mOhm@Vgs=4.5V,PowerPAK1212,8P,G | VISHAY ENTER TECHNO LOGY.INC | SIS412DN-T1-GE3 | G | PWA BOM | In New BOM |
|  |  |  | 51030U700-223-G | MOS N,NTMFS4823NT1G,30V,10.8A,18m@4.5V,G,SO-8FL,SMD | ON SEMICONDUCTOR CORP | NTMFS4823NT1G | G | PWA BOM | In New BOM |
|  |  |  | 51031BT00-223-G | MOS N,NTTFS4930NTAG,30V,7.2A,30m@4.5V,G,WDFN-8,SMD | ON SEMICONDUCTOR CORP | NTTFS4930NTAG | G | PWA BOM | In New BOM |
|  | Q5 | 1 | 51030S400-185-G | MOS N,FDMC8884,30V,9A,30m@4.5V,G,Power33-8,SMD | FAIRCHILD SEMICONDUCTOR CORP | FDMC8884 | G | PWA BOM | In Old BOM |
|  |  |  | 510505E00-221-G | MOS N/N,BSC150N03LD G,30V,8A,22m@4.5V,G,TDSON-8,SMD | INFINEON | BSC150N03LD G | G | PWA BOM | In Old BOM |
|  |  |  | 51030SM00-029-G | MOSFET-N,SIS412DN-T1-GE3,30V,12A,24mOhm@Vgs=10V,30mOhm@Vgs=4.5V,PowerPAK1212,8P,G | VISHAY ENTER TECHNO LOGY.INC | SIS412DN-T1-GE3 | G | PWA BOM | In Old BOM |
|  |  |  | 51030U700-223-G | MOS N,NTMFS4823NT1G,30V,10.8A,18m@4.5V,G,SO-8FL,SMD | ON SEMICONDUCTOR CORP | NTMFS4823NT1G | G | PWA BOM | In Old BOM |
|  |  |  | 51031BT00-223-G | MOS N,NTTFS4930NTAG,30V,7.2A,30m@4.5V,G,WDFN-8,SMD | ON SEMICONDUCTOR CORP | NTTFS4930NTAG | G | PWA BOM | In Old BOM |
| ##### Change Revision |  |  |  |  |  |  |  |  |  |
| Sheet | REV OF BOM | CUSTOMER | CUSTOMER P/N | PWA PN | PWA DESCRIPTION | PWA REV | DATE | Remark |  |
| OOOOOOOOOOOOOOOOOOOOOOOOOOOOOOOOOOOOOOOOOOOOOOOOOOOOOOOOOOOOOOOOOOOOOOOOOOOOOOOOOOOOOOOOOO | OOOOOOOOOOOOOOOOOOOOOOOOOOOOOOOOOOOOOOOOOOOOOOOOOOOOOOOOOOOOOOOOOOOOOOOOOOOOOOOOOOOOOOOOOO | OOOOOOOOOOOOOOOOOOOOOOOOOOOOOOOOOOOOOOOOOOOOOOOOOOOOOOOOOOOOOOOOOOOOOOOOOOOOOOOOOOOOOOOOOO | OOOOOOOOOOOOOOOOOOOOOOOOOOOOOOOOOOOOOOOOOOOOOOOOOOOOOOOOOOOOOOOOOOOOOOOOOOOOOOOOOOOOOOOOOO | OOOOOOOOOOOOOOOOOOOOOOOOOOOOOOOOOOOOOOOOOOOOOOOOOOOOOOOOOOOOOOOOOOOOOOOOOOOOOOOOOOOOOOOOOO | OOOOOOOOOOOOOOOOOOOOOOOOOOOOOOOOOOOOOOOOOOOOOOOOOOOOOOOOOOOOOOOOOOOOOOOOOOOOOOOOOOOOOOOOOO | OOOOOOOOOOOOOOOOOOOOOOOOOOOOOOOOOOOOOOOOOOOOOOOOOOOOOOOOOOOOOOOOOOOOOOOOOOOOOOOOOOOOOOOOOO | OOOOOOOOOOOOOOOOOOOOOOOOOOOOOOOOOOOOOOOOOOOOOOOOOOOOOOOOOOOOOOOOOOOOOOOOOOOOOOOOOOOOOOOOOO | OOOOOOOOOOOOOOOOOOOOOOOOOOOOOOOOOOOOOOOOOOOOOOOOOOOOOOOOOOOOOOOOOOOOOOOOOOOOOOOOOOOOOOOOOO | OOOOOOOOOOOOOOOOOOOOOOOOOOOOOOOOOOOOOOOOOOOOOOOOOOOOOOOOOOOOOOOOOOOOOOOOOOOOOOOOOOOOOOOOOO |
| Second Source Change |  |  |  |  |  |  |  |  |  |
| Item | Location | Change Type | Foxconn P/N | Part Description | Manufacturer Full Name | Manufacturer P/N | RoHS | Sheet |  |
| 1 | L24 |  | 720101L00-015-G | FB,600 Ohm@100MHz,+/-25%,200mA,500mOhm,G,SMD0603 | MURATA ELEC. NORTH AMERICA | BLM18AG601SN1D | G | PWA BOM |  |
|  |  | NO | 720101L00-074-G | FB,600Ohm@100MHz,+/-25%,200mA,500mOhm,SMD0603,G | CHILISIN ELECTRONICS CORP. | SBK160808T-601Y-N | G | PWA BOM |  |
|  |  | NO | 720105E04-016-G | FB,600Ohm@100MHz,+/-25%,500mA,400mOhm,SMD0603,G | TDK ELECTRONICS EUROPE GMBH | MMZ1608B601CTAH0 | G | PWA BOM |  |
|  |  | Delete | 720101L00-026-G | FB,600 Ohm@100MHz,+/-25%,200mA,500mOhm,G,SMD0603 | SAMSUNG SEMICONDUCTOR | CIM10U601NC | G | PWA BOM |  |
| 2 | Q5 |  | 51030S400-185-G | MOS N,FDMC8884,30V,9A,30m@4.5V,G,Power33-8,SMD | FAIRCHILD SEMICONDUCTOR CORP | FDMC8884 | G | PWA BOM |  |
|  |  | NO | 51030SM00-029-G | MOSFET-N,SIS412DN-T1-GE3,30V,12A,24mOhm@Vgs=10V,30mOhm@Vgs=4.5V,PowerPAK1212,8P,G | VISHAY ENTER TECHNO LOGY.INC | SIS412DN-T1-GE3 | G | PWA BOM |  |
|  |  | NO | 51030U700-223-G | MOS N,NTMFS4823NT1G,30V,10.8A,18m@4.5V,G,SO-8FL,SMD | ON SEMICONDUCTOR CORP | NTMFS4823NT1G | G | PWA BOM |  |
|  |  | NO | 51031BT00-223-G | MOS N,NTTFS4930NTAG,30V,7.2A,30m@4.5V,G,WDFN-8,SMD | ON SEMICONDUCTOR CORP | NTTFS4930NTAG | G | PWA BOM |  |
|  |  | Delete | 510505E00-221-G | MOS N/N,BSC150N03LD G,30V,8A,22m@4.5V,G,TDSON-8,SMD | INFINEON | BSC150N03LD G | G | PWA BOM |  |
| OOOOOOOOOOOOOOOOOOOOOOOOOOOOOOOOOOOOOOOOOOOOOOOOOOOOOOOOOOOOOOOOOOOOOOOOOOOOOOOOOOOOOOOOOO | OOOOOOOOOOOOOOOOOOOOOOOOOOOOOOOOOOOOOOOOOOOOOOOOOOOOOOOOOOOOOOOOOOOOOOOOOOOOOOOOOOOOOOOOOO | OOOOOOOOOOOOOOOOOOOOOOOOOOOOOOOOOOOOOOOOOOOOOOOOOOOOOOOOOOOOOOOOOOOOOOOOOOOOOOOOOOOOOOOOOO | OOOOOOOOOOOOOOOOOOOOOOOOOOOOOOOOOOOOOOOOOOOOOOOOOOOOOOOOOOOOOOOOOOOOOOOOOOOOOOOOOOOOOOOOOO | OOOOOOOOOOOOOOOOOOOOOOOOOOOOOOOOOOOOOOOOOOOOOOOOOOOOOOOOOOOOOOOOOOOOOOOOOOOOOOOOOOOOOOOOOO | OOOOOOOOOOOOOOOOOOOOOOOOOOOOOOOOOOOOOOOOOOOOOOOOOOOOOOOOOOOOOOOOOOOOOOOOOOOOOOOOOOOOOOOOOO | OOOOOOOOOOOOOOOOOOOOOOOOOOOOOOOOOOOOOOOOOOOOOOOOOOOOOOOOOOOOOOOOOOOOOOOOOOOOOOOOOOOOOOOOOO | OOOOOOOOOOOOOOOOOOOOOOOOOOOOOOOOOOOOOOOOOOOOOOOOOOOOOOOOOOOOOOOOOOOOOOOOOOOOOOOOOOOOOOOOOO | OOOOOOOOOOOOOOOOOOOOOOOOOOOOOOOOOOOOOOOOOOOOOOOOOOOOOOOOOOOOOOOOOOOOOOOOOOOOOOOOOOOOOOOOOO | OOOOOOOOOOOOOOOOOOOOOOOOOOOOOOOOOOOOOOOOOOOOOOOOOOOOOOOOOOOOOOOOOOOOOOOOOOOOOOOOOOOOOOOOOO |
| Master Materials Change |  |  |  |  |  |  |  |  |  |
| Item | Foxconn P/N | Orig._Usage | New_Usage | Part Description | Manufacturer Full Name | Manufacturer P/N | RoHS | Location | Sheet |
| OOOOOOOOOOOOOOOOOOOOOOOOOOOOOOOOOOOOOOOOOOOOOOOOOOOOOOOOOOOOOOOOOOOOOOOOOOOOOOOOOOOOOOOOOO | OOOOOOOOOOOOOOOOOOOOOOOOOOOOOOOOOOOOOOOOOOOOOOOOOOOOOOOOOOOOOOOOOOOOOOOOOOOOOOOOOOOOOOOOOO | OOOOOOOOOOOOOOOOOOOOOOOOOOOOOOOOOOOOOOOOOOOOOOOOOOOOOOOOOOOOOOOOOOOOOOOOOOOOOOOOOOOOOOOOOO | OOOOOOOOOOOOOOOOOOOOOOOOOOOOOOOOOOOOOOOOOOOOOOOOOOOOOOOOOOOOOOOOOOOOOOOOOOOOOOOOOOOOOOOOOO | OOOOOOOOOOOOOOOOOOOOOOOOOOOOOOOOOOOOOOOOOOOOOOOOOOOOOOOOOOOOOOOOOOOOOOOOOOOOOOOOOOOOOOOOOO | OOOOOOOOOOOOOOOOOOOOOOOOOOOOOOOOOOOOOOOOOOOOOOOOOOOOOOOOOOOOOOOOOOOOOOOOOOOOOOOOOOOOOOOOOO | OOOOOOOOOOOOOOOOOOOOOOOOOOOOOOOOOOOOOOOOOOOOOOOOOOOOOOOOOOOOOOOOOOOOOOOOOOOOOOOOOOOOOOOOOO | OOOOOOOOOOOOOOOOOOOOOOOOOOOOOOOOOOOOOOOOOOOOOOOOOOOOOOOOOOOOOOOOOOOOOOOOOOOOOOOOOOOOOOOOOO | OOOOOOOOOOOOOOOOOOOOOOOOOOOOOOOOOOOOOOOOOOOOOOOOOOOOOOOOOOOOOOOOOOOOOOOOOOOOOOOOOOOOOOOOOO | OOOOOOOOOOOOOOOOOOOOOOOOOOOOOOOOOOOOOOOOOOOOOOOOOOOOOOOOOOOOOOOOOOOOOOOOOOOOOOOOOOOOOOOOOO |
| TLA Parts Change |  |  |  |  |  |  |  |  |  |
| Item | Foxconn P/N | Qty | Part Description | Manufacturer Full Name | Manufacturer P/N | RoHS | Location | Remark | BOM |
| BOM Change List Date:Wed Dec 20 15:30:08 GMT+08:00 2017 |  |  |  |  |  |  |  |  |  |
| New BOM file : E:\barreleye g2\1218\EXPANDER 1218.xls |  |  |  |  |  |  |  |  |  |
| Old BOM file : E:\barreleye g2\1218\EXPANDER 1208.xls |  |  |  |  |  |  |  |  |  |
| ##### Add Parts |  |  |  |  |  |  |  |  |  |
| Item | Location | Qty | Foxconn P/N | Part Description | Manufacturer Full Name | Manufacturer P/N | RoHS | Sheet |  |
| ##### Remove Parts |  |  |  |  |  |  |  |  |  |
| Item | Location | Qty | Foxconn P/N | Part Description | Manufacturer Full Name | Manufacturer P/N | RoHS | Sheet |  |
| ##### Change Parts |  |  |  |  |  |  |  |  |  |
| Item | Location | Qty | Foxconn P/N | Part Description | Manufacturer Full Name | Manufacturer P/N | RoHS | Sheet | Remark |
| 1 | Q5 | 1 | 51030S400-185-G | MOS N,FDMC8884,30V,9A,30m@4.5V,G,Power33-8,SMD | FAIRCHILD SEMICONDUCTOR CORP | FDMC8884 | G | PWA BOM | In New BOM |
|  |  |  | 51031D300-221-G | MOS N,BSZ0909NS,34V,36A,15m@4.5V,G,SON-8,SMD | INFINEON TECHNOLOGIES CORP. | BSZ0909NS | G | PWA BOM | In New BOM |
|  |  |  | 51030SM00-029-G | MOSFET-N,SIS412DN-T1-GE3,30V,12A,24mOhm@Vgs=10V,30mOhm@Vgs=4.5V,PowerPAK1212,8P,G | VISHAY ENTER TECHNO LOGY.INC | SIS412DN-T1-GE3 | G | PWA BOM | In New BOM |
|  |  |  | 51031BT00-223-G | MOS N,NTTFS4930NTAG,30V,7.2A,30m@4.5V,G,WDFN-8,SMD | ON SEMICONDUCTOR CORP | NTTFS4930NTAG | G | PWA BOM | In New BOM |
|  | Q5 | 1 | 51030S400-185-G | MOS N,FDMC8884,30V,9A,30m@4.5V,G,Power33-8,SMD | FAIRCHILD SEMICONDUCTOR CORP | FDMC8884 | G | PWA BOM | In Old BOM |
|  |  |  | 51030SM00-029-G | MOSFET-N,SIS412DN-T1-GE3,30V,12A,24mOhm@Vgs=10V,30mOhm@Vgs=4.5V,PowerPAK1212,8P,G | VISHAY ENTER TECHNO LOGY.INC | SIS412DN-T1-GE3 | G | PWA BOM | In Old BOM |
|  |  |  | 51030U700-223-G | MOS N,NTMFS4823NT1G,30V,10.8A,18m@4.5V,G,SO-8FL,SMD | ON SEMICONDUCTOR CORP | NTMFS4823NT1G | G | PWA BOM | In Old BOM |
|  |  |  | 51031BT00-223-G | MOS N,NTTFS4930NTAG,30V,7.2A,30m@4.5V,G,WDFN-8,SMD | ON SEMICONDUCTOR CORP | NTTFS4930NTAG | G | PWA BOM | In Old BOM |
| ##### Change Revision |  |  |  |  |  |  |  |  |  |
| Sheet | REV OF BOM | CUSTOMER | CUSTOMER P/N | PWA PN | PWA DESCRIPTION | PWA REV | DATE | Remark |  |
| OOOOOOOOOOOOOOOOOOOOOOOOOOOOOOOOOOOOOOOOOOOOOOOOOOOOOOOOOOOOOOOOOOOOOOOOOOOOOOOOOOOOOOOOOO | OOOOOOOOOOOOOOOOOOOOOOOOOOOOOOOOOOOOOOOOOOOOOOOOOOOOOOOOOOOOOOOOOOOOOOOOOOOOOOOOOOOOOOOOOO | OOOOOOOOOOOOOOOOOOOOOOOOOOOOOOOOOOOOOOOOOOOOOOOOOOOOOOOOOOOOOOOOOOOOOOOOOOOOOOOOOOOOOOOOOO | OOOOOOOOOOOOOOOOOOOOOOOOOOOOOOOOOOOOOOOOOOOOOOOOOOOOOOOOOOOOOOOOOOOOOOOOOOOOOOOOOOOOOOOOOO | OOOOOOOOOOOOOOOOOOOOOOOOOOOOOOOOOOOOOOOOOOOOOOOOOOOOOOOOOOOOOOOOOOOOOOOOOOOOOOOOOOOOOOOOOO | OOOOOOOOOOOOOOOOOOOOOOOOOOOOOOOOOOOOOOOOOOOOOOOOOOOOOOOOOOOOOOOOOOOOOOOOOOOOOOOOOOOOOOOOOO | OOOOOOOOOOOOOOOOOOOOOOOOOOOOOOOOOOOOOOOOOOOOOOOOOOOOOOOOOOOOOOOOOOOOOOOOOOOOOOOOOOOOOOOOOO | OOOOOOOOOOOOOOOOOOOOOOOOOOOOOOOOOOOOOOOOOOOOOOOOOOOOOOOOOOOOOOOOOOOOOOOOOOOOOOOOOOOOOOOOOO | OOOOOOOOOOOOOOOOOOOOOOOOOOOOOOOOOOOOOOOOOOOOOOOOOOOOOOOOOOOOOOOOOOOOOOOOOOOOOOOOOOOOOOOOOO | OOOOOOOOOOOOOOOOOOOOOOOOOOOOOOOOOOOOOOOOOOOOOOOOOOOOOOOOOOOOOOOOOOOOOOOOOOOOOOOOOOOOOOOOOO |
| Second Source Change |  |  |  |  |  |  |  |  |  |
| Item | Location | Change Type | Foxconn P/N | Part Description | Manufacturer Full Name | Manufacturer P/N | RoHS | Sheet |  |
| 1 | Q5 |  | 51030S400-185-G | MOS N,FDMC8884,30V,9A,30m@4.5V,G,Power33-8,SMD | FAIRCHILD SEMICONDUCTOR CORP | FDMC8884 | G | PWA BOM |  |
|  |  | ADD | 51031D300-221-G | MOS N,BSZ0909NS,34V,36A,15m@4.5V,G,SON-8,SMD | INFINEON TECHNOLOGIES CORP. | BSZ0909NS | G | PWA BOM |  |
|  |  | NO | 51030SM00-029-G | MOSFET-N,SIS412DN-T1-GE3,30V,12A,24mOhm@Vgs=10V,30mOhm@Vgs=4.5V,PowerPAK1212,8P,G | VISHAY ENTER TECHNO LOGY.INC | SIS412DN-T1-GE3 | G | PWA BOM |  |
|  |  | NO | 51031BT00-223-G | MOS N,NTTFS4930NTAG,30V,7.2A,30m@4.5V,G,WDFN-8,SMD | ON SEMICONDUCTOR CORP | NTTFS4930NTAG | G | PWA BOM |  |
|  |  | Delete | 51030U700-223-G | MOS N,NTMFS4823NT1G,30V,10.8A,18m@4.5V,G,SO-8FL,SMD | ON SEMICONDUCTOR CORP | NTMFS4823NT1G | G | PWA BOM |  |
| OOOOOOOOOOOOOOOOOOOOOOOOOOOOOOOOOOOOOOOOOOOOOOOOOOOOOOOOOOOOOOOOOOOOOOOOOOOOOOOOOOOOOOOOOO | OOOOOOOOOOOOOOOOOOOOOOOOOOOOOOOOOOOOOOOOOOOOOOOOOOOOOOOOOOOOOOOOOOOOOOOOOOOOOOOOOOOOOOOOOO | OOOOOOOOOOOOOOOOOOOOOOOOOOOOOOOOOOOOOOOOOOOOOOOOOOOOOOOOOOOOOOOOOOOOOOOOOOOOOOOOOOOOOOOOOO | OOOOOOOOOOOOOOOOOOOOOOOOOOOOOOOOOOOOOOOOOOOOOOOOOOOOOOOOOOOOOOOOOOOOOOOOOOOOOOOOOOOOOOOOOO | OOOOOOOOOOOOOOOOOOOOOOOOOOOOOOOOOOOOOOOOOOOOOOOOOOOOOOOOOOOOOOOOOOOOOOOOOOOOOOOOOOOOOOOOOO | OOOOOOOOOOOOOOOOOOOOOOOOOOOOOOOOOOOOOOOOOOOOOOOOOOOOOOOOOOOOOOOOOOOOOOOOOOOOOOOOOOOOOOOOOO | OOOOOOOOOOOOOOOOOOOOOOOOOOOOOOOOOOOOOOOOOOOOOOOOOOOOOOOOOOOOOOOOOOOOOOOOOOOOOOOOOOOOOOOOOO | OOOOOOOOOOOOOOOOOOOOOOOOOOOOOOOOOOOOOOOOOOOOOOOOOOOOOOOOOOOOOOOOOOOOOOOOOOOOOOOOOOOOOOOOOO | OOOOOOOOOOOOOOOOOOOOOOOOOOOOOOOOOOOOOOOOOOOOOOOOOOOOOOOOOOOOOOOOOOOOOOOOOOOOOOOOOOOOOOOOOO | OOOOOOOOOOOOOOOOOOOOOOOOOOOOOOOOOOOOOOOOOOOOOOOOOOOOOOOOOOOOOOOOOOOOOOOOOOOOOOOOOOOOOOOOOO |
| Master Materials Change |  |  |  |  |  |  |  |  |  |
| Item | Foxconn P/N | Orig._Usage | New_Usage | Part Description | Manufacturer Full Name | Manufacturer P/N | RoHS | Location | Sheet |
| OOOOOOOOOOOOOOOOOOOOOOOOOOOOOOOOOOOOOOOOOOOOOOOOOOOOOOOOOOOOOOOOOOOOOOOOOOOOOOOOOOOOOOOOOO | OOOOOOOOOOOOOOOOOOOOOOOOOOOOOOOOOOOOOOOOOOOOOOOOOOOOOOOOOOOOOOOOOOOOOOOOOOOOOOOOOOOOOOOOOO | OOOOOOOOOOOOOOOOOOOOOOOOOOOOOOOOOOOOOOOOOOOOOOOOOOOOOOOOOOOOOOOOOOOOOOOOOOOOOOOOOOOOOOOOOO | OOOOOOOOOOOOOOOOOOOOOOOOOOOOOOOOOOOOOOOOOOOOOOOOOOOOOOOOOOOOOOOOOOOOOOOOOOOOOOOOOOOOOOOOOO | OOOOOOOOOOOOOOOOOOOOOOOOOOOOOOOOOOOOOOOOOOOOOOOOOOOOOOOOOOOOOOOOOOOOOOOOOOOOOOOOOOOOOOOOOO | OOOOOOOOOOOOOOOOOOOOOOOOOOOOOOOOOOOOOOOOOOOOOOOOOOOOOOOOOOOOOOOOOOOOOOOOOOOOOOOOOOOOOOOOOO | OOOOOOOOOOOOOOOOOOOOOOOOOOOOOOOOOOOOOOOOOOOOOOOOOOOOOOOOOOOOOOOOOOOOOOOOOOOOOOOOOOOOOOOOOO | OOOOOOOOOOOOOOOOOOOOOOOOOOOOOOOOOOOOOOOOOOOOOOOOOOOOOOOOOOOOOOOOOOOOOOOOOOOOOOOOOOOOOOOOOO | OOOOOOOOOOOOOOOOOOOOOOOOOOOOOOOOOOOOOOOOOOOOOOOOOOOOOOOOOOOOOOOOOOOOOOOOOOOOOOOOOOOOOOOOOO | OOOOOOOOOOOOOOOOOOOOOOOOOOOOOOOOOOOOOOOOOOOOOOOOOOOOOOOOOOOOOOOOOOOOOOOOOOOOOOOOOOOOOOOOOO |
| TLA Parts Change |  |  |  |  |  |  |  |  |  |
| Item | Foxconn P/N | Qty | Part Description | Manufacturer Full Name | Manufacturer P/N | RoHS | Location | Remark | BOM |
